FILE_TYPE = MACRO_DRAWING;
SET COLOR_WIRE YELLOW;
SET COLOR_PROP ORANGE;
SET COLOR_DOT WHITE;
SET COLOR_ARC YELLOW;
SET COLOR_BODY GREEN;
SET COLOR_NOTE PURPLE;
SET PROP_DISPLAY VALUE;
SET PAGE_NUMBER P142;
FORCEADD UNIVERSAL_GND..1
(-150 250);
FORCEPROP 3 LASTPIN (-150 300) SIG_NAME GND\g
J 0
(-140 310);
DISPLAY 0.659574 (-140 310);
PAINT MONO (-140 310);
DISPLAY INVISIBLE (-140 310);
FORCEPROP 2 LAST CDS_LIB logical_power
J 0
(-150 250);
DISPLAY INVISIBLE (-150 250);
FORCEPROP 1 LAST HDL_POWER GND
J 1
(-125 175);
DISPLAY 0.872340 (-125 175);
PAINT GREEN (-125 175);
DISPLAY INVISIBLE (-125 175);
FORCEPROP 1 LAST PATH I1
J 0
(-75 250);
DISPLAY 0.872340 (-75 250);
PAINT AQUA (-75 250);
DISPLAY INVISIBLE (-75 250);
FORCEADD OFFPAGE..1
(-1250 1550);
FORCEPROP 2 LAST $XR0 173 
J 0
(-1502 1550);
DISPLAY 0.638298 (-1502 1550);
PAINT MONO (-1502 1550);
FORCEPROP 2 LAST CDS_LIB standard
J 0
(-1250 1550);
DISPLAY INVISIBLE (-1250 1550);
FORCEPROP 1 LAST COMMENT_BODY TRUE
J 0
(-1125 1450);
DISPLAY 0.872340 (-1125 1450);
PAINT GREEN (-1125 1450);
DISPLAY INVISIBLE (-1125 1450);
FORCEPROP 1 LAST OFFPAGE TRUE
J 0
(-925 1425);
DISPLAY 0.872340 (-925 1425);
PAINT AQUA (-925 1425);
DISPLAY INVISIBLE (-925 1425);
FORCEPROP 2 LAST PATH I10
J 0
(-1200 1625);
DISPLAY 1.021277 (-1200 1625);
DISPLAY INVISIBLE (-1200 1625);
FORCEADD OFFPAGE..1
(-1250 1500);
FORCEPROP 2 LAST $XR0 173 
J 0
(-1502 1500);
DISPLAY 0.638298 (-1502 1500);
PAINT MONO (-1502 1500);
FORCEPROP 2 LAST CDS_LIB standard
J 0
(-1250 1500);
DISPLAY INVISIBLE (-1250 1500);
FORCEPROP 1 LAST COMMENT_BODY TRUE
J 0
(-1125 1400);
DISPLAY 0.872340 (-1125 1400);
PAINT GREEN (-1125 1400);
DISPLAY INVISIBLE (-1125 1400);
FORCEPROP 1 LAST OFFPAGE TRUE
J 0
(-925 1375);
DISPLAY 0.872340 (-925 1375);
PAINT AQUA (-925 1375);
DISPLAY INVISIBLE (-925 1375);
FORCEPROP 2 LAST PATH I11
J 0
(-1200 1575);
DISPLAY 1.021277 (-1200 1575);
DISPLAY INVISIBLE (-1200 1575);
FORCEADD OFFPAGE..1
(-1250 1650);
FORCEPROP 2 LAST $XR0 174 
J 0
(-1502 1650);
DISPLAY 0.638298 (-1502 1650);
PAINT MONO (-1502 1650);
FORCEPROP 2 LAST CDS_LIB standard
J 0
(-1250 1650);
DISPLAY INVISIBLE (-1250 1650);
FORCEPROP 1 LAST OFFPAGE TRUE
J 0
(-925 1525);
DISPLAY 0.872340 (-925 1525);
PAINT AQUA (-925 1525);
DISPLAY INVISIBLE (-925 1525);
FORCEPROP 1 LAST COMMENT_BODY TRUE
J 0
(-1125 1550);
DISPLAY 0.872340 (-1125 1550);
PAINT GREEN (-1125 1550);
DISPLAY INVISIBLE (-1125 1550);
FORCEPROP 2 LAST PATH I12
J 0
(-1200 1725);
DISPLAY 1.021277 (-1200 1725);
DISPLAY INVISIBLE (-1200 1725);
FORCEADD OFFPAGE..1
(-1250 1700);
FORCEPROP 2 LAST $XR0 174 
J 0
(-1502 1700);
DISPLAY 0.638298 (-1502 1700);
PAINT MONO (-1502 1700);
FORCEPROP 2 LAST CDS_LIB standard
J 0
(-1250 1700);
DISPLAY INVISIBLE (-1250 1700);
FORCEPROP 1 LAST OFFPAGE TRUE
J 0
(-925 1575);
DISPLAY 0.872340 (-925 1575);
PAINT AQUA (-925 1575);
DISPLAY INVISIBLE (-925 1575);
FORCEPROP 1 LAST COMMENT_BODY TRUE
J 0
(-1125 1600);
DISPLAY 0.872340 (-1125 1600);
PAINT GREEN (-1125 1600);
DISPLAY INVISIBLE (-1125 1600);
FORCEPROP 2 LAST PATH I13
J 0
(-1200 1775);
DISPLAY 1.021277 (-1200 1775);
DISPLAY INVISIBLE (-1200 1775);
FORCEADD OFFPAGE..2
R 2
(-1250 1850);
FORCEPROP 2 LAST $XR0 30 
J 0
(-1504 1850);
DISPLAY 0.638298 (-1504 1850);
PAINT MONO (-1504 1850);
FORCEPROP 2 LAST CDS_LIB standard
J 0
(-1250 1850);
DISPLAY INVISIBLE (-1250 1850);
FORCEPROP 1 LAST COMMENT_BODY TRUE
J 2
(-1205 1755);
DISPLAY 0.872340 (-1205 1755);
PAINT GREEN (-1205 1755);
DISPLAY INVISIBLE (-1205 1755);
FORCEPROP 1 LAST OFFPAGE TRUE
J 2
(-1575 1725);
DISPLAY 0.872340 (-1575 1725);
PAINT AQUA (-1575 1725);
DISPLAY INVISIBLE (-1575 1725);
FORCEPROP 2 LAST PATH I14
J 0
(-1200 1925);
DISPLAY 1.021277 (-1200 1925);
DISPLAY INVISIBLE (-1200 1925);
FORCEADD OFFPAGE..5
(-1250 1800);
FORCEPROP 2 LAST $XR0 30 
J 0
(-1504 1800);
DISPLAY 0.638298 (-1504 1800);
PAINT MONO (-1504 1800);
FORCEPROP 2 LAST CDS_LIB standard
J 0
(-1250 1800);
DISPLAY INVISIBLE (-1250 1800);
FORCEPROP 1 LAST COMMENT_BODY TRUE
J 0
(-1150 1725);
DISPLAY 1.170213 (-1150 1725);
PAINT GREEN (-1150 1725);
DISPLAY INVISIBLE (-1150 1725);
FORCEPROP 1 LAST OFFPAGE TRUE
J 0
(-925 1675);
DISPLAY 0.872340 (-925 1675);
PAINT AQUA (-925 1675);
DISPLAY INVISIBLE (-925 1675);
FORCEPROP 2 LAST PATH I15
J 0
(-1200 1875);
DISPLAY 1.021277 (-1200 1875);
DISPLAY INVISIBLE (-1200 1875);
FORCEADD OFFPAGE..5
(-1250 1950);
FORCEPROP 2 LAST $XR0 30 
J 0
(-1504 1950);
DISPLAY 0.638298 (-1504 1950);
PAINT MONO (-1504 1950);
FORCEPROP 2 LAST CDS_LIB standard
J 0
(-1250 1950);
DISPLAY INVISIBLE (-1250 1950);
FORCEPROP 1 LAST COMMENT_BODY TRUE
J 0
(-1150 1875);
DISPLAY 1.170213 (-1150 1875);
PAINT GREEN (-1150 1875);
DISPLAY INVISIBLE (-1150 1875);
FORCEPROP 1 LAST OFFPAGE TRUE
J 0
(-925 1825);
DISPLAY 0.872340 (-925 1825);
PAINT AQUA (-925 1825);
DISPLAY INVISIBLE (-925 1825);
FORCEPROP 2 LAST PATH I16
J 0
(-1200 2025);
DISPLAY 1.021277 (-1200 2025);
DISPLAY INVISIBLE (-1200 2025);
FORCEADD OFFPAGE..2
R 2
(-1250 2000);
FORCEPROP 2 LAST $XR0 30 
J 0
(-1504 2000);
DISPLAY 0.638298 (-1504 2000);
PAINT MONO (-1504 2000);
FORCEPROP 2 LAST CDS_LIB standard
J 0
(-1250 2000);
DISPLAY INVISIBLE (-1250 2000);
FORCEPROP 1 LAST COMMENT_BODY TRUE
J 2
(-1205 1905);
DISPLAY 0.872340 (-1205 1905);
PAINT GREEN (-1205 1905);
DISPLAY INVISIBLE (-1205 1905);
FORCEPROP 1 LAST OFFPAGE TRUE
J 2
(-1575 1875);
DISPLAY 0.872340 (-1575 1875);
PAINT AQUA (-1575 1875);
DISPLAY INVISIBLE (-1575 1875);
FORCEPROP 2 LAST PATH I17
J 0
(-1200 2075);
DISPLAY 1.021277 (-1200 2075);
DISPLAY INVISIBLE (-1200 2075);
FORCEADD OFFPAGE..1
(-1250 2250);
FORCEPROP 2 LAST $XR0 173 
J 0
(-1502 2250);
DISPLAY 0.638298 (-1502 2250);
PAINT MONO (-1502 2250);
FORCEPROP 2 LAST CDS_LIB standard
J 0
(-1250 2250);
DISPLAY INVISIBLE (-1250 2250);
FORCEPROP 1 LAST OFFPAGE TRUE
J 0
(-925 2125);
DISPLAY 0.872340 (-925 2125);
PAINT AQUA (-925 2125);
DISPLAY INVISIBLE (-925 2125);
FORCEPROP 1 LAST COMMENT_BODY TRUE
J 0
(-1125 2150);
DISPLAY 0.872340 (-1125 2150);
PAINT GREEN (-1125 2150);
DISPLAY INVISIBLE (-1125 2150);
FORCEPROP 2 LAST PATH I18
J 0
(-1200 2325);
DISPLAY 1.021277 (-1200 2325);
DISPLAY INVISIBLE (-1200 2325);
FORCEADD OFFPAGE..1
(-1250 2300);
FORCEPROP 2 LAST $XR0 173 
J 0
(-1502 2300);
DISPLAY 0.638298 (-1502 2300);
PAINT MONO (-1502 2300);
FORCEPROP 2 LAST CDS_LIB standard
J 0
(-1250 2300);
DISPLAY INVISIBLE (-1250 2300);
FORCEPROP 1 LAST COMMENT_BODY TRUE
J 0
(-1125 2200);
DISPLAY 0.872340 (-1125 2200);
PAINT GREEN (-1125 2200);
DISPLAY INVISIBLE (-1125 2200);
FORCEPROP 1 LAST OFFPAGE TRUE
J 0
(-925 2175);
DISPLAY 0.872340 (-925 2175);
PAINT AQUA (-925 2175);
DISPLAY INVISIBLE (-925 2175);
FORCEPROP 2 LAST PATH I19
J 0
(-1200 2375);
DISPLAY 1.021277 (-1200 2375);
DISPLAY INVISIBLE (-1200 2375);
FORCEADD OFFPAGE..1
(-1250 650);
FORCEPROP 2 LAST $XR0 173 
J 0
(-1502 650);
DISPLAY 0.638298 (-1502 650);
PAINT MONO (-1502 650);
FORCEPROP 2 LAST CDS_LIB standard
J 0
(-1250 650);
DISPLAY INVISIBLE (-1250 650);
FORCEPROP 1 LAST COMMENT_BODY TRUE
J 0
(-1125 550);
DISPLAY 0.872340 (-1125 550);
PAINT GREEN (-1125 550);
DISPLAY INVISIBLE (-1125 550);
FORCEPROP 1 LAST OFFPAGE TRUE
J 0
(-925 525);
DISPLAY 0.872340 (-925 525);
PAINT AQUA (-925 525);
DISPLAY INVISIBLE (-925 525);
FORCEPROP 2 LAST PATH I2
J 0
(-1200 725);
DISPLAY 1.021277 (-1200 725);
DISPLAY INVISIBLE (-1200 725);
FORCEADD OFFPAGE..1
(-1250 2400);
FORCEPROP 2 LAST $XR0 174 
J 0
(-1502 2400);
DISPLAY 0.638298 (-1502 2400);
PAINT MONO (-1502 2400);
FORCEPROP 2 LAST CDS_LIB standard
J 0
(-1250 2400);
DISPLAY INVISIBLE (-1250 2400);
FORCEPROP 1 LAST OFFPAGE TRUE
J 0
(-925 2275);
DISPLAY 0.872340 (-925 2275);
PAINT AQUA (-925 2275);
DISPLAY INVISIBLE (-925 2275);
FORCEPROP 1 LAST COMMENT_BODY TRUE
J 0
(-1125 2300);
DISPLAY 0.872340 (-1125 2300);
PAINT GREEN (-1125 2300);
DISPLAY INVISIBLE (-1125 2300);
FORCEPROP 2 LAST PATH I20
J 0
(-1200 2475);
DISPLAY 1.021277 (-1200 2475);
DISPLAY INVISIBLE (-1200 2475);
FORCEADD OFFPAGE..1
(-1250 2450);
FORCEPROP 2 LAST $XR0 174 
J 0
(-1502 2450);
DISPLAY 0.638298 (-1502 2450);
PAINT MONO (-1502 2450);
FORCEPROP 2 LAST CDS_LIB standard
J 0
(-1250 2450);
DISPLAY INVISIBLE (-1250 2450);
FORCEPROP 1 LAST COMMENT_BODY TRUE
J 0
(-1125 2350);
DISPLAY 0.872340 (-1125 2350);
PAINT GREEN (-1125 2350);
DISPLAY INVISIBLE (-1125 2350);
FORCEPROP 1 LAST OFFPAGE TRUE
J 0
(-925 2325);
DISPLAY 0.872340 (-925 2325);
PAINT AQUA (-925 2325);
DISPLAY INVISIBLE (-925 2325);
FORCEPROP 2 LAST PATH I21
J 0
(-1200 2525);
DISPLAY 1.021277 (-1200 2525);
DISPLAY INVISIBLE (-1200 2525);
FORCEADD OFFPAGE..5
(-1250 2550);
FORCEPROP 2 LAST $XR0 30 
J 0
(-1504 2550);
DISPLAY 0.638298 (-1504 2550);
PAINT MONO (-1504 2550);
FORCEPROP 2 LAST CDS_LIB standard
J 0
(-1250 2550);
DISPLAY INVISIBLE (-1250 2550);
FORCEPROP 1 LAST OFFPAGE TRUE
J 0
(-925 2425);
DISPLAY 0.872340 (-925 2425);
PAINT AQUA (-925 2425);
DISPLAY INVISIBLE (-925 2425);
FORCEPROP 1 LAST COMMENT_BODY TRUE
J 0
(-1150 2475);
DISPLAY 1.170213 (-1150 2475);
PAINT GREEN (-1150 2475);
DISPLAY INVISIBLE (-1150 2475);
FORCEPROP 2 LAST PATH I22
J 0
(-1200 2625);
DISPLAY 1.021277 (-1200 2625);
DISPLAY INVISIBLE (-1200 2625);
FORCEADD OFFPAGE..2
R 2
(-1250 2600);
FORCEPROP 2 LAST $XR0 30 
J 0
(-1504 2600);
DISPLAY 0.638298 (-1504 2600);
PAINT MONO (-1504 2600);
FORCEPROP 2 LAST CDS_LIB standard
J 0
(-1250 2600);
DISPLAY INVISIBLE (-1250 2600);
FORCEPROP 1 LAST OFFPAGE TRUE
J 2
(-1575 2475);
DISPLAY 0.872340 (-1575 2475);
PAINT AQUA (-1575 2475);
DISPLAY INVISIBLE (-1575 2475);
FORCEPROP 1 LAST COMMENT_BODY TRUE
J 2
(-1205 2505);
DISPLAY 0.872340 (-1205 2505);
PAINT GREEN (-1205 2505);
DISPLAY INVISIBLE (-1205 2505);
FORCEPROP 2 LAST PATH I23
J 0
(-1200 2675);
DISPLAY 1.021277 (-1200 2675);
DISPLAY INVISIBLE (-1200 2675);
FORCEADD OFFPAGE..5
(-1250 2700);
FORCEPROP 2 LAST $XR0 30 
J 0
(-1504 2700);
DISPLAY 0.638298 (-1504 2700);
PAINT MONO (-1504 2700);
FORCEPROP 2 LAST CDS_LIB standard
J 0
(-1250 2700);
DISPLAY INVISIBLE (-1250 2700);
FORCEPROP 1 LAST OFFPAGE TRUE
J 0
(-925 2575);
DISPLAY 0.872340 (-925 2575);
PAINT AQUA (-925 2575);
DISPLAY INVISIBLE (-925 2575);
FORCEPROP 1 LAST COMMENT_BODY TRUE
J 0
(-1150 2625);
DISPLAY 1.170213 (-1150 2625);
PAINT GREEN (-1150 2625);
DISPLAY INVISIBLE (-1150 2625);
FORCEPROP 2 LAST PATH I24
J 0
(-1200 2775);
DISPLAY 1.021277 (-1200 2775);
DISPLAY INVISIBLE (-1200 2775);
FORCEADD OFFPAGE..2
R 2
(-1250 2750);
FORCEPROP 2 LAST $XR0 30 
J 0
(-1504 2750);
DISPLAY 0.638298 (-1504 2750);
PAINT MONO (-1504 2750);
FORCEPROP 2 LAST CDS_LIB standard
J 0
(-1250 2750);
DISPLAY INVISIBLE (-1250 2750);
FORCEPROP 1 LAST OFFPAGE TRUE
J 2
(-1575 2625);
DISPLAY 0.872340 (-1575 2625);
PAINT AQUA (-1575 2625);
DISPLAY INVISIBLE (-1575 2625);
FORCEPROP 1 LAST COMMENT_BODY TRUE
J 2
(-1205 2655);
DISPLAY 0.872340 (-1205 2655);
PAINT GREEN (-1205 2655);
DISPLAY INVISIBLE (-1205 2655);
FORCEPROP 2 LAST PATH I25
J 0
(-1200 2825);
DISPLAY 1.021277 (-1200 2825);
DISPLAY INVISIBLE (-1200 2825);
FORCEADD OFFPAGE..1
(-1250 3150);
FORCEPROP 2 LAST $XR0 173 
J 0
(-1502 3150);
DISPLAY 0.638298 (-1502 3150);
PAINT MONO (-1502 3150);
FORCEPROP 2 LAST CDS_LIB standard
J 0
(-1250 3150);
DISPLAY INVISIBLE (-1250 3150);
FORCEPROP 1 LAST OFFPAGE TRUE
J 0
(-925 3025);
DISPLAY 0.872340 (-925 3025);
PAINT AQUA (-925 3025);
DISPLAY INVISIBLE (-925 3025);
FORCEPROP 1 LAST COMMENT_BODY TRUE
J 0
(-1125 3050);
DISPLAY 0.872340 (-1125 3050);
PAINT GREEN (-1125 3050);
DISPLAY INVISIBLE (-1125 3050);
FORCEPROP 2 LAST PATH I26
J 0
(-1200 3225);
DISPLAY 1.021277 (-1200 3225);
DISPLAY INVISIBLE (-1200 3225);
FORCEADD OFFPAGE..1
(-1250 3100);
FORCEPROP 2 LAST $XR0 173 
J 0
(-1502 3100);
DISPLAY 0.638298 (-1502 3100);
PAINT MONO (-1502 3100);
FORCEPROP 2 LAST CDS_LIB standard
J 0
(-1250 3100);
DISPLAY INVISIBLE (-1250 3100);
FORCEPROP 1 LAST OFFPAGE TRUE
J 0
(-925 2975);
DISPLAY 0.872340 (-925 2975);
PAINT AQUA (-925 2975);
DISPLAY INVISIBLE (-925 2975);
FORCEPROP 1 LAST COMMENT_BODY TRUE
J 0
(-1125 3000);
DISPLAY 0.872340 (-1125 3000);
PAINT GREEN (-1125 3000);
DISPLAY INVISIBLE (-1125 3000);
FORCEPROP 2 LAST PATH I27
J 0
(-1200 3175);
DISPLAY 1.021277 (-1200 3175);
DISPLAY INVISIBLE (-1200 3175);
FORCEADD OFFPAGE..1
(-1250 3250);
FORCEPROP 2 LAST $XR0 174 
J 0
(-1502 3250);
DISPLAY 0.638298 (-1502 3250);
PAINT MONO (-1502 3250);
FORCEPROP 2 LAST CDS_LIB standard
J 0
(-1250 3250);
DISPLAY INVISIBLE (-1250 3250);
FORCEPROP 1 LAST COMMENT_BODY TRUE
J 0
(-1125 3150);
DISPLAY 0.872340 (-1125 3150);
PAINT GREEN (-1125 3150);
DISPLAY INVISIBLE (-1125 3150);
FORCEPROP 1 LAST OFFPAGE TRUE
J 0
(-925 3125);
DISPLAY 0.872340 (-925 3125);
PAINT AQUA (-925 3125);
DISPLAY INVISIBLE (-925 3125);
FORCEPROP 2 LAST PATH I28
J 0
(-1200 3325);
DISPLAY 1.021277 (-1200 3325);
DISPLAY INVISIBLE (-1200 3325);
FORCEADD OFFPAGE..1
(-1250 3300);
FORCEPROP 2 LAST $XR0 174 
J 0
(-1502 3300);
DISPLAY 0.638298 (-1502 3300);
PAINT MONO (-1502 3300);
FORCEPROP 2 LAST CDS_LIB standard
J 0
(-1250 3300);
DISPLAY INVISIBLE (-1250 3300);
FORCEPROP 1 LAST OFFPAGE TRUE
J 0
(-925 3175);
DISPLAY 0.872340 (-925 3175);
PAINT AQUA (-925 3175);
DISPLAY INVISIBLE (-925 3175);
FORCEPROP 1 LAST COMMENT_BODY TRUE
J 0
(-1125 3200);
DISPLAY 0.872340 (-1125 3200);
PAINT GREEN (-1125 3200);
DISPLAY INVISIBLE (-1125 3200);
FORCEPROP 2 LAST PATH I29
J 0
(-1200 3375);
DISPLAY 1.021277 (-1200 3375);
DISPLAY INVISIBLE (-1200 3375);
FORCEADD OFFPAGE..1
(-1250 850);
FORCEPROP 2 LAST $XR0 174 
J 0
(-1502 850);
DISPLAY 0.638298 (-1502 850);
PAINT MONO (-1502 850);
FORCEPROP 2 LAST CDS_LIB standard
J 0
(-1250 850);
DISPLAY INVISIBLE (-1250 850);
FORCEPROP 1 LAST COMMENT_BODY TRUE
J 0
(-1125 750);
DISPLAY 0.872340 (-1125 750);
PAINT GREEN (-1125 750);
DISPLAY INVISIBLE (-1125 750);
FORCEPROP 1 LAST OFFPAGE TRUE
J 0
(-925 725);
DISPLAY 0.872340 (-925 725);
PAINT AQUA (-925 725);
DISPLAY INVISIBLE (-925 725);
FORCEPROP 2 LAST PATH I3
J 0
(-1200 925);
DISPLAY 1.021277 (-1200 925);
DISPLAY INVISIBLE (-1200 925);
FORCEADD OFFPAGE..5
(-1250 3400);
FORCEPROP 2 LAST $XR0 30 
J 0
(-1504 3400);
DISPLAY 0.638298 (-1504 3400);
PAINT MONO (-1504 3400);
FORCEPROP 2 LAST CDS_LIB standard
J 0
(-1250 3400);
DISPLAY INVISIBLE (-1250 3400);
FORCEPROP 1 LAST OFFPAGE TRUE
J 0
(-925 3275);
DISPLAY 0.872340 (-925 3275);
PAINT AQUA (-925 3275);
DISPLAY INVISIBLE (-925 3275);
FORCEPROP 1 LAST COMMENT_BODY TRUE
J 0
(-1150 3325);
DISPLAY 1.170213 (-1150 3325);
PAINT GREEN (-1150 3325);
DISPLAY INVISIBLE (-1150 3325);
FORCEPROP 2 LAST PATH I30
J 0
(-1200 3475);
DISPLAY 1.021277 (-1200 3475);
DISPLAY INVISIBLE (-1200 3475);
FORCEADD OFFPAGE..2
R 2
(-1250 3450);
FORCEPROP 2 LAST $XR0 30 
J 0
(-1504 3450);
DISPLAY 0.638298 (-1504 3450);
PAINT MONO (-1504 3450);
FORCEPROP 2 LAST CDS_LIB standard
J 0
(-1250 3450);
DISPLAY INVISIBLE (-1250 3450);
FORCEPROP 1 LAST OFFPAGE TRUE
J 2
(-1575 3325);
DISPLAY 0.872340 (-1575 3325);
PAINT AQUA (-1575 3325);
DISPLAY INVISIBLE (-1575 3325);
FORCEPROP 1 LAST COMMENT_BODY TRUE
J 2
(-1205 3355);
DISPLAY 0.872340 (-1205 3355);
PAINT GREEN (-1205 3355);
DISPLAY INVISIBLE (-1205 3355);
FORCEPROP 2 LAST PATH I31
J 0
(-1200 3525);
DISPLAY 1.021277 (-1200 3525);
DISPLAY INVISIBLE (-1200 3525);
FORCEADD OFFPAGE..5
(-1250 3550);
FORCEPROP 2 LAST $XR0 30 
J 0
(-1504 3550);
DISPLAY 0.638298 (-1504 3550);
PAINT MONO (-1504 3550);
FORCEPROP 2 LAST CDS_LIB standard
J 0
(-1250 3550);
DISPLAY INVISIBLE (-1250 3550);
FORCEPROP 1 LAST COMMENT_BODY TRUE
J 0
(-1150 3475);
DISPLAY 1.170213 (-1150 3475);
PAINT GREEN (-1150 3475);
DISPLAY INVISIBLE (-1150 3475);
FORCEPROP 1 LAST OFFPAGE TRUE
J 0
(-925 3425);
DISPLAY 0.872340 (-925 3425);
PAINT AQUA (-925 3425);
DISPLAY INVISIBLE (-925 3425);
FORCEPROP 2 LAST PATH I32
J 0
(-1200 3625);
DISPLAY 1.021277 (-1200 3625);
DISPLAY INVISIBLE (-1200 3625);
FORCEADD OFFPAGE..2
R 2
(-1250 3600);
FORCEPROP 2 LAST $XR0 30 
J 0
(-1504 3600);
DISPLAY 0.638298 (-1504 3600);
PAINT MONO (-1504 3600);
FORCEPROP 2 LAST CDS_LIB standard
J 0
(-1250 3600);
DISPLAY INVISIBLE (-1250 3600);
FORCEPROP 1 LAST COMMENT_BODY TRUE
J 2
(-1205 3505);
DISPLAY 0.872340 (-1205 3505);
PAINT GREEN (-1205 3505);
DISPLAY INVISIBLE (-1205 3505);
FORCEPROP 1 LAST OFFPAGE TRUE
J 2
(-1575 3475);
DISPLAY 0.872340 (-1575 3475);
PAINT AQUA (-1575 3475);
DISPLAY INVISIBLE (-1575 3475);
FORCEPROP 2 LAST PATH I33
J 0
(-1200 3675);
DISPLAY 1.021277 (-1200 3675);
DISPLAY INVISIBLE (-1200 3675);
FORCEADD UNIVERSAL_GND..1
(4725 200);
FORCEPROP 3 LASTPIN (4725 250) SIG_NAME GND\g
J 0
(4735 260);
DISPLAY 0.659574 (4735 260);
PAINT MONO (4735 260);
DISPLAY INVISIBLE (4735 260);
FORCEPROP 2 LAST CDS_LIB logical_power
J 0
(4725 200);
DISPLAY INVISIBLE (4725 200);
FORCEPROP 1 LAST HDL_POWER GND
J 1
(4750 125);
DISPLAY 0.872340 (4750 125);
PAINT GREEN (4750 125);
DISPLAY INVISIBLE (4750 125);
FORCEPROP 1 LAST PATH I34
J 0
(4800 200);
DISPLAY 0.872340 (4800 200);
PAINT AQUA (4800 200);
DISPLAY INVISIBLE (4800 200);
FORCEADD OFFPAGE..1
(3675 650);
FORCEPROP 2 LAST $XR0 173 
J 0
(3423 650);
DISPLAY 0.638298 (3423 650);
PAINT MONO (3423 650);
FORCEPROP 2 LAST CDS_LIB standard
J 0
(3675 650);
DISPLAY INVISIBLE (3675 650);
FORCEPROP 1 LAST COMMENT_BODY TRUE
J 0
(3800 550);
DISPLAY 0.872340 (3800 550);
PAINT GREEN (3800 550);
DISPLAY INVISIBLE (3800 550);
FORCEPROP 1 LAST OFFPAGE TRUE
J 0
(4000 525);
DISPLAY 0.872340 (4000 525);
PAINT AQUA (4000 525);
DISPLAY INVISIBLE (4000 525);
FORCEPROP 2 LAST PATH I35
J 0
(3725 725);
DISPLAY 1.021277 (3725 725);
DISPLAY INVISIBLE (3725 725);
FORCEADD OFFPAGE..1
(3675 700);
FORCEPROP 2 LAST $XR0 173 
J 0
(3423 700);
DISPLAY 0.638298 (3423 700);
PAINT MONO (3423 700);
FORCEPROP 2 LAST CDS_LIB standard
J 0
(3675 700);
DISPLAY INVISIBLE (3675 700);
FORCEPROP 1 LAST COMMENT_BODY TRUE
J 0
(3800 600);
DISPLAY 0.872340 (3800 600);
PAINT GREEN (3800 600);
DISPLAY INVISIBLE (3800 600);
FORCEPROP 1 LAST OFFPAGE TRUE
J 0
(4000 575);
DISPLAY 0.872340 (4000 575);
PAINT AQUA (4000 575);
DISPLAY INVISIBLE (4000 575);
FORCEPROP 2 LAST PATH I36
J 0
(3725 775);
DISPLAY 1.021277 (3725 775);
DISPLAY INVISIBLE (3725 775);
FORCEADD OFFPAGE..1
(3675 800);
FORCEPROP 2 LAST $XR0 174 
J 0
(3423 800);
DISPLAY 0.638298 (3423 800);
PAINT MONO (3423 800);
FORCEPROP 2 LAST CDS_LIB standard
J 0
(3675 800);
DISPLAY INVISIBLE (3675 800);
FORCEPROP 1 LAST OFFPAGE TRUE
J 0
(4000 675);
DISPLAY 0.872340 (4000 675);
PAINT AQUA (4000 675);
DISPLAY INVISIBLE (4000 675);
FORCEPROP 1 LAST COMMENT_BODY TRUE
J 0
(3800 700);
DISPLAY 0.872340 (3800 700);
PAINT GREEN (3800 700);
DISPLAY INVISIBLE (3800 700);
FORCEPROP 2 LAST PATH I37
J 0
(3725 875);
DISPLAY 1.021277 (3725 875);
DISPLAY INVISIBLE (3725 875);
FORCEADD OFFPAGE..1
(3675 850);
FORCEPROP 2 LAST $XR0 174 
J 0
(3423 850);
DISPLAY 0.638298 (3423 850);
PAINT MONO (3423 850);
FORCEPROP 2 LAST CDS_LIB standard
J 0
(3675 850);
DISPLAY INVISIBLE (3675 850);
FORCEPROP 1 LAST OFFPAGE TRUE
J 0
(4000 725);
DISPLAY 0.872340 (4000 725);
PAINT AQUA (4000 725);
DISPLAY INVISIBLE (4000 725);
FORCEPROP 1 LAST COMMENT_BODY TRUE
J 0
(3800 750);
DISPLAY 0.872340 (3800 750);
PAINT GREEN (3800 750);
DISPLAY INVISIBLE (3800 750);
FORCEPROP 2 LAST PATH I38
J 0
(3725 925);
DISPLAY 1.021277 (3725 925);
DISPLAY INVISIBLE (3725 925);
FORCEADD OFFPAGE..5
(3675 950);
FORCEPROP 2 LAST $XR0 30 
J 0
(3451 950);
DISPLAY 0.638298 (3451 950);
PAINT MONO (3451 950);
FORCEPROP 2 LAST CDS_LIB standard
J 0
(3675 950);
DISPLAY INVISIBLE (3675 950);
FORCEPROP 1 LAST COMMENT_BODY TRUE
J 0
(3775 875);
DISPLAY 1.170213 (3775 875);
PAINT GREEN (3775 875);
DISPLAY INVISIBLE (3775 875);
FORCEPROP 1 LAST OFFPAGE TRUE
J 0
(4000 825);
DISPLAY 0.872340 (4000 825);
PAINT AQUA (4000 825);
DISPLAY INVISIBLE (4000 825);
FORCEPROP 2 LAST PATH I39
J 0
(3725 1025);
DISPLAY 1.021277 (3725 1025);
DISPLAY INVISIBLE (3725 1025);
FORCEADD OFFPAGE..1
(-1250 700);
FORCEPROP 2 LAST $XR0 173 
J 0
(-1502 700);
DISPLAY 0.638298 (-1502 700);
PAINT MONO (-1502 700);
FORCEPROP 2 LAST CDS_LIB standard
J 0
(-1250 700);
DISPLAY INVISIBLE (-1250 700);
FORCEPROP 1 LAST COMMENT_BODY TRUE
J 0
(-1125 600);
DISPLAY 0.872340 (-1125 600);
PAINT GREEN (-1125 600);
DISPLAY INVISIBLE (-1125 600);
FORCEPROP 1 LAST OFFPAGE TRUE
J 0
(-925 575);
DISPLAY 0.872340 (-925 575);
PAINT AQUA (-925 575);
DISPLAY INVISIBLE (-925 575);
FORCEPROP 2 LAST PATH I4
J 0
(-1200 775);
DISPLAY 1.021277 (-1200 775);
DISPLAY INVISIBLE (-1200 775);
FORCEADD OFFPAGE..2
R 2
(3675 1000);
FORCEPROP 2 LAST $XR0 30 
J 0
(3451 1000);
DISPLAY 0.638298 (3451 1000);
PAINT MONO (3451 1000);
FORCEPROP 2 LAST CDS_LIB standard
J 0
(3675 1000);
DISPLAY INVISIBLE (3675 1000);
FORCEPROP 1 LAST COMMENT_BODY TRUE
J 2
(3720 905);
DISPLAY 0.872340 (3720 905);
PAINT GREEN (3720 905);
DISPLAY INVISIBLE (3720 905);
FORCEPROP 1 LAST OFFPAGE TRUE
J 2
(3350 875);
DISPLAY 0.872340 (3350 875);
PAINT AQUA (3350 875);
DISPLAY INVISIBLE (3350 875);
FORCEPROP 2 LAST PATH I40
J 0
(3725 1075);
DISPLAY 1.021277 (3725 1075);
DISPLAY INVISIBLE (3725 1075);
FORCEADD OFFPAGE..5
(3675 1100);
FORCEPROP 2 LAST $XR0 30 
J 0
(3451 1100);
DISPLAY 0.638298 (3451 1100);
PAINT MONO (3451 1100);
FORCEPROP 2 LAST CDS_LIB standard
J 0
(3675 1100);
DISPLAY INVISIBLE (3675 1100);
FORCEPROP 1 LAST COMMENT_BODY TRUE
J 0
(3775 1025);
DISPLAY 1.170213 (3775 1025);
PAINT GREEN (3775 1025);
DISPLAY INVISIBLE (3775 1025);
FORCEPROP 1 LAST OFFPAGE TRUE
J 0
(4000 975);
DISPLAY 0.872340 (4000 975);
PAINT AQUA (4000 975);
DISPLAY INVISIBLE (4000 975);
FORCEPROP 2 LAST PATH I41
J 0
(3725 1175);
DISPLAY 1.021277 (3725 1175);
DISPLAY INVISIBLE (3725 1175);
FORCEADD OFFPAGE..2
R 2
(3675 1150);
FORCEPROP 2 LAST $XR0 30 
J 0
(3451 1150);
DISPLAY 0.638298 (3451 1150);
PAINT MONO (3451 1150);
FORCEPROP 2 LAST CDS_LIB standard
J 0
(3675 1150);
DISPLAY INVISIBLE (3675 1150);
FORCEPROP 1 LAST COMMENT_BODY TRUE
J 2
(3720 1055);
DISPLAY 0.872340 (3720 1055);
PAINT GREEN (3720 1055);
DISPLAY INVISIBLE (3720 1055);
FORCEPROP 1 LAST OFFPAGE TRUE
J 2
(3350 1025);
DISPLAY 0.872340 (3350 1025);
PAINT AQUA (3350 1025);
DISPLAY INVISIBLE (3350 1025);
FORCEPROP 2 LAST PATH I42
J 0
(3725 1225);
DISPLAY 1.021277 (3725 1225);
DISPLAY INVISIBLE (3725 1225);
FORCEADD OFFPAGE..1
(3675 1650);
FORCEPROP 2 LAST $XR0 174 
J 0
(3423 1650);
DISPLAY 0.638298 (3423 1650);
PAINT MONO (3423 1650);
FORCEPROP 2 LAST CDS_LIB standard
J 0
(3675 1650);
DISPLAY INVISIBLE (3675 1650);
FORCEPROP 1 LAST COMMENT_BODY TRUE
J 0
(3800 1550);
DISPLAY 0.872340 (3800 1550);
PAINT GREEN (3800 1550);
DISPLAY INVISIBLE (3800 1550);
FORCEPROP 1 LAST OFFPAGE TRUE
J 0
(4000 1525);
DISPLAY 0.872340 (4000 1525);
PAINT AQUA (4000 1525);
DISPLAY INVISIBLE (4000 1525);
FORCEPROP 2 LAST PATH I43
J 0
(3725 1725);
DISPLAY 1.021277 (3725 1725);
DISPLAY INVISIBLE (3725 1725);
FORCEADD OFFPAGE..1
(3675 1700);
FORCEPROP 2 LAST $XR0 174 
J 0
(3423 1700);
DISPLAY 0.638298 (3423 1700);
PAINT MONO (3423 1700);
FORCEPROP 2 LAST CDS_LIB standard
J 0
(3675 1700);
DISPLAY INVISIBLE (3675 1700);
FORCEPROP 1 LAST COMMENT_BODY TRUE
J 0
(3800 1600);
DISPLAY 0.872340 (3800 1600);
PAINT GREEN (3800 1600);
DISPLAY INVISIBLE (3800 1600);
FORCEPROP 1 LAST OFFPAGE TRUE
J 0
(4000 1575);
DISPLAY 0.872340 (4000 1575);
PAINT AQUA (4000 1575);
DISPLAY INVISIBLE (4000 1575);
FORCEPROP 2 LAST PATH I44
J 0
(3725 1775);
DISPLAY 1.021277 (3725 1775);
DISPLAY INVISIBLE (3725 1775);
FORCEADD OFFPAGE..5
(3675 1800);
FORCEPROP 2 LAST $XR0 30 
J 0
(3451 1800);
DISPLAY 0.638298 (3451 1800);
PAINT MONO (3451 1800);
FORCEPROP 2 LAST CDS_LIB standard
J 0
(3675 1800);
DISPLAY INVISIBLE (3675 1800);
FORCEPROP 1 LAST OFFPAGE TRUE
J 0
(4000 1675);
DISPLAY 0.872340 (4000 1675);
PAINT AQUA (4000 1675);
DISPLAY INVISIBLE (4000 1675);
FORCEPROP 1 LAST COMMENT_BODY TRUE
J 0
(3775 1725);
DISPLAY 1.170213 (3775 1725);
PAINT GREEN (3775 1725);
DISPLAY INVISIBLE (3775 1725);
FORCEPROP 2 LAST PATH I45
J 0
(3725 1875);
DISPLAY 1.021277 (3725 1875);
DISPLAY INVISIBLE (3725 1875);
FORCEADD OFFPAGE..2
R 2
(3675 1850);
FORCEPROP 2 LAST $XR0 30 
J 0
(3451 1850);
DISPLAY 0.638298 (3451 1850);
PAINT MONO (3451 1850);
FORCEPROP 2 LAST CDS_LIB standard
J 0
(3675 1850);
DISPLAY INVISIBLE (3675 1850);
FORCEPROP 1 LAST OFFPAGE TRUE
J 2
(3350 1725);
DISPLAY 0.872340 (3350 1725);
PAINT AQUA (3350 1725);
DISPLAY INVISIBLE (3350 1725);
FORCEPROP 1 LAST COMMENT_BODY TRUE
J 2
(3720 1755);
DISPLAY 0.872340 (3720 1755);
PAINT GREEN (3720 1755);
DISPLAY INVISIBLE (3720 1755);
FORCEPROP 2 LAST PATH I46
J 0
(3725 1925);
DISPLAY 1.021277 (3725 1925);
DISPLAY INVISIBLE (3725 1925);
FORCEADD OFFPAGE..5
(3675 1950);
FORCEPROP 2 LAST $XR0 30 
J 0
(3451 1950);
DISPLAY 0.638298 (3451 1950);
PAINT MONO (3451 1950);
FORCEPROP 2 LAST CDS_LIB standard
J 0
(3675 1950);
DISPLAY INVISIBLE (3675 1950);
FORCEPROP 1 LAST COMMENT_BODY TRUE
J 0
(3775 1875);
DISPLAY 1.170213 (3775 1875);
PAINT GREEN (3775 1875);
DISPLAY INVISIBLE (3775 1875);
FORCEPROP 1 LAST OFFPAGE TRUE
J 0
(4000 1825);
DISPLAY 0.872340 (4000 1825);
PAINT AQUA (4000 1825);
DISPLAY INVISIBLE (4000 1825);
FORCEPROP 2 LAST PATH I47
J 0
(3725 2025);
DISPLAY 1.021277 (3725 2025);
DISPLAY INVISIBLE (3725 2025);
FORCEADD OFFPAGE..2
R 2
(3675 2000);
FORCEPROP 2 LAST $XR0 30 
J 0
(3451 2000);
DISPLAY 0.638298 (3451 2000);
PAINT MONO (3451 2000);
FORCEPROP 2 LAST CDS_LIB standard
J 0
(3675 2000);
DISPLAY INVISIBLE (3675 2000);
FORCEPROP 1 LAST COMMENT_BODY TRUE
J 2
(3720 1905);
DISPLAY 0.872340 (3720 1905);
PAINT GREEN (3720 1905);
DISPLAY INVISIBLE (3720 1905);
FORCEPROP 1 LAST OFFPAGE TRUE
J 2
(3350 1875);
DISPLAY 0.872340 (3350 1875);
PAINT AQUA (3350 1875);
DISPLAY INVISIBLE (3350 1875);
FORCEPROP 2 LAST PATH I48
J 0
(3725 2075);
DISPLAY 1.021277 (3725 2075);
DISPLAY INVISIBLE (3725 2075);
FORCEADD OFFPAGE..1
(3650 2250);
FORCEPROP 2 LAST $XR0 173 
J 0
(3368 2250);
DISPLAY 0.638298 (3368 2250);
PAINT MONO (3368 2250);
FORCEPROP 2 LAST CDS_LIB standard
J 0
(3650 2250);
DISPLAY INVISIBLE (3650 2250);
FORCEPROP 1 LAST OFFPAGE TRUE
J 0
(3975 2125);
DISPLAY 0.872340 (3975 2125);
PAINT AQUA (3975 2125);
DISPLAY INVISIBLE (3975 2125);
FORCEPROP 1 LAST COMMENT_BODY TRUE
J 0
(3775 2150);
DISPLAY 0.872340 (3775 2150);
PAINT GREEN (3775 2150);
DISPLAY INVISIBLE (3775 2150);
FORCEPROP 2 LAST PATH I49
J 0
(3700 2325);
DISPLAY 1.021277 (3700 2325);
DISPLAY INVISIBLE (3700 2325);
FORCEADD OFFPAGE..1
(-1250 800);
FORCEPROP 2 LAST $XR0 174 
J 0
(-1502 800);
DISPLAY 0.638298 (-1502 800);
PAINT MONO (-1502 800);
FORCEPROP 2 LAST CDS_LIB standard
J 0
(-1250 800);
DISPLAY INVISIBLE (-1250 800);
FORCEPROP 1 LAST COMMENT_BODY TRUE
J 0
(-1125 700);
DISPLAY 0.872340 (-1125 700);
PAINT GREEN (-1125 700);
DISPLAY INVISIBLE (-1125 700);
FORCEPROP 1 LAST OFFPAGE TRUE
J 0
(-925 675);
DISPLAY 0.872340 (-925 675);
PAINT AQUA (-925 675);
DISPLAY INVISIBLE (-925 675);
FORCEPROP 2 LAST PATH I5
J 0
(-1200 875);
DISPLAY 1.021277 (-1200 875);
DISPLAY INVISIBLE (-1200 875);
FORCEADD OFFPAGE..1
(3650 2400);
FORCEPROP 2 LAST $XR0 174 
J 0
(3368 2400);
DISPLAY 0.638298 (3368 2400);
PAINT MONO (3368 2400);
FORCEPROP 2 LAST CDS_LIB standard
J 0
(3650 2400);
DISPLAY INVISIBLE (3650 2400);
FORCEPROP 1 LAST OFFPAGE TRUE
J 0
(3975 2275);
DISPLAY 0.872340 (3975 2275);
PAINT AQUA (3975 2275);
DISPLAY INVISIBLE (3975 2275);
FORCEPROP 1 LAST COMMENT_BODY TRUE
J 0
(3775 2300);
DISPLAY 0.872340 (3775 2300);
PAINT GREEN (3775 2300);
DISPLAY INVISIBLE (3775 2300);
FORCEPROP 2 LAST PATH I50
J 0
(3700 2475);
DISPLAY 1.021277 (3700 2475);
DISPLAY INVISIBLE (3700 2475);
FORCEADD OFFPAGE..1
(3650 2300);
FORCEPROP 2 LAST $XR0 173 
J 0
(3368 2300);
DISPLAY 0.638298 (3368 2300);
PAINT MONO (3368 2300);
FORCEPROP 2 LAST CDS_LIB standard
J 0
(3650 2300);
DISPLAY INVISIBLE (3650 2300);
FORCEPROP 1 LAST COMMENT_BODY TRUE
J 0
(3775 2200);
DISPLAY 0.872340 (3775 2200);
PAINT GREEN (3775 2200);
DISPLAY INVISIBLE (3775 2200);
FORCEPROP 1 LAST OFFPAGE TRUE
J 0
(3975 2175);
DISPLAY 0.872340 (3975 2175);
PAINT AQUA (3975 2175);
DISPLAY INVISIBLE (3975 2175);
FORCEPROP 2 LAST PATH I51
J 0
(3700 2375);
DISPLAY 1.021277 (3700 2375);
DISPLAY INVISIBLE (3700 2375);
FORCEADD OFFPAGE..1
(3650 2450);
FORCEPROP 2 LAST $XR0 174 
J 0
(3368 2450);
DISPLAY 0.638298 (3368 2450);
PAINT MONO (3368 2450);
FORCEPROP 2 LAST CDS_LIB standard
J 0
(3650 2450);
DISPLAY INVISIBLE (3650 2450);
FORCEPROP 1 LAST COMMENT_BODY TRUE
J 0
(3775 2350);
DISPLAY 0.872340 (3775 2350);
PAINT GREEN (3775 2350);
DISPLAY INVISIBLE (3775 2350);
FORCEPROP 1 LAST OFFPAGE TRUE
J 0
(3975 2325);
DISPLAY 0.872340 (3975 2325);
PAINT AQUA (3975 2325);
DISPLAY INVISIBLE (3975 2325);
FORCEPROP 2 LAST PATH I52
J 0
(3700 2525);
DISPLAY 1.021277 (3700 2525);
DISPLAY INVISIBLE (3700 2525);
FORCEADD OFFPAGE..5
(3650 2550);
FORCEPROP 2 LAST $XR0 30 
J 0
(3426 2550);
DISPLAY 0.638298 (3426 2550);
PAINT MONO (3426 2550);
FORCEPROP 2 LAST CDS_LIB standard
J 0
(3650 2550);
DISPLAY INVISIBLE (3650 2550);
FORCEPROP 1 LAST COMMENT_BODY TRUE
J 0
(3750 2475);
DISPLAY 1.170213 (3750 2475);
PAINT GREEN (3750 2475);
DISPLAY INVISIBLE (3750 2475);
FORCEPROP 1 LAST OFFPAGE TRUE
J 0
(3975 2425);
DISPLAY 0.872340 (3975 2425);
PAINT AQUA (3975 2425);
DISPLAY INVISIBLE (3975 2425);
FORCEPROP 2 LAST PATH I53
J 0
(3700 2625);
DISPLAY 1.021277 (3700 2625);
DISPLAY INVISIBLE (3700 2625);
FORCEADD OFFPAGE..2
R 2
(3650 2600);
FORCEPROP 2 LAST $XR0 30 
J 0
(3426 2600);
DISPLAY 0.638298 (3426 2600);
PAINT MONO (3426 2600);
FORCEPROP 2 LAST CDS_LIB standard
J 0
(3650 2600);
DISPLAY INVISIBLE (3650 2600);
FORCEPROP 1 LAST COMMENT_BODY TRUE
J 2
(3695 2505);
DISPLAY 0.872340 (3695 2505);
PAINT GREEN (3695 2505);
DISPLAY INVISIBLE (3695 2505);
FORCEPROP 1 LAST OFFPAGE TRUE
J 2
(3325 2475);
DISPLAY 0.872340 (3325 2475);
PAINT AQUA (3325 2475);
DISPLAY INVISIBLE (3325 2475);
FORCEPROP 2 LAST PATH I54
J 0
(3700 2675);
DISPLAY 1.021277 (3700 2675);
DISPLAY INVISIBLE (3700 2675);
FORCEADD OFFPAGE..5
(3650 2700);
FORCEPROP 2 LAST $XR0 30 
J 0
(3426 2700);
DISPLAY 0.638298 (3426 2700);
PAINT MONO (3426 2700);
FORCEPROP 2 LAST CDS_LIB standard
J 0
(3650 2700);
DISPLAY INVISIBLE (3650 2700);
FORCEPROP 1 LAST COMMENT_BODY TRUE
J 0
(3750 2625);
DISPLAY 1.170213 (3750 2625);
PAINT GREEN (3750 2625);
DISPLAY INVISIBLE (3750 2625);
FORCEPROP 1 LAST OFFPAGE TRUE
J 0
(3975 2575);
DISPLAY 0.872340 (3975 2575);
PAINT AQUA (3975 2575);
DISPLAY INVISIBLE (3975 2575);
FORCEPROP 2 LAST PATH I55
J 0
(3700 2775);
DISPLAY 1.021277 (3700 2775);
DISPLAY INVISIBLE (3700 2775);
FORCEADD OFFPAGE..2
R 2
(3650 2750);
FORCEPROP 2 LAST $XR0 30 
J 0
(3426 2750);
DISPLAY 0.638298 (3426 2750);
PAINT MONO (3426 2750);
FORCEPROP 2 LAST CDS_LIB standard
J 0
(3650 2750);
DISPLAY INVISIBLE (3650 2750);
FORCEPROP 1 LAST COMMENT_BODY TRUE
J 2
(3695 2655);
DISPLAY 0.872340 (3695 2655);
PAINT GREEN (3695 2655);
DISPLAY INVISIBLE (3695 2655);
FORCEPROP 1 LAST OFFPAGE TRUE
J 2
(3325 2625);
DISPLAY 0.872340 (3325 2625);
PAINT AQUA (3325 2625);
DISPLAY INVISIBLE (3325 2625);
FORCEPROP 2 LAST PATH I56
J 0
(3700 2825);
DISPLAY 1.021277 (3700 2825);
DISPLAY INVISIBLE (3700 2825);
FORCEADD OFFPAGE..1
(3650 3100);
FORCEPROP 2 LAST $XR0 173 
J 0
(3368 3100);
DISPLAY 0.638298 (3368 3100);
PAINT MONO (3368 3100);
FORCEPROP 1 LAST COMMENT_BODY TRUE
J 0
(3775 3000);
DISPLAY 0.872340 (3775 3000);
PAINT GREEN (3775 3000);
DISPLAY INVISIBLE (3775 3000);
FORCEPROP 1 LAST OFFPAGE TRUE
J 0
(3975 2975);
DISPLAY 0.872340 (3975 2975);
PAINT AQUA (3975 2975);
DISPLAY INVISIBLE (3975 2975);
FORCEPROP 2 LAST PATH I57
J 0
(3700 3175);
DISPLAY 1.021277 (3700 3175);
DISPLAY INVISIBLE (3700 3175);
FORCEPROP 2 LAST CDS_LIB standard
J 0
(3650 3100);
DISPLAY INVISIBLE (3650 3100);
FORCEADD OFFPAGE..1
(3650 3150);
FORCEPROP 2 LAST $XR0 173 
J 0
(3368 3150);
DISPLAY 0.638298 (3368 3150);
PAINT MONO (3368 3150);
FORCEPROP 2 LAST CDS_LIB standard
J 0
(3650 3150);
DISPLAY INVISIBLE (3650 3150);
FORCEPROP 1 LAST COMMENT_BODY TRUE
J 0
(3775 3050);
DISPLAY 0.872340 (3775 3050);
PAINT GREEN (3775 3050);
DISPLAY INVISIBLE (3775 3050);
FORCEPROP 1 LAST OFFPAGE TRUE
J 0
(3975 3025);
DISPLAY 0.872340 (3975 3025);
PAINT AQUA (3975 3025);
DISPLAY INVISIBLE (3975 3025);
FORCEPROP 2 LAST PATH I58
J 0
(3700 3225);
DISPLAY 1.021277 (3700 3225);
DISPLAY INVISIBLE (3700 3225);
FORCEADD OFFPAGE..1
(3650 3250);
FORCEPROP 2 LAST $XR0 174 
J 0
(3368 3250);
DISPLAY 0.638298 (3368 3250);
PAINT MONO (3368 3250);
FORCEPROP 2 LAST CDS_LIB standard
J 0
(3650 3250);
DISPLAY INVISIBLE (3650 3250);
FORCEPROP 1 LAST COMMENT_BODY TRUE
J 0
(3775 3150);
DISPLAY 0.872340 (3775 3150);
PAINT GREEN (3775 3150);
DISPLAY INVISIBLE (3775 3150);
FORCEPROP 1 LAST OFFPAGE TRUE
J 0
(3975 3125);
DISPLAY 0.872340 (3975 3125);
PAINT AQUA (3975 3125);
DISPLAY INVISIBLE (3975 3125);
FORCEPROP 2 LAST PATH I59
J 0
(3700 3325);
DISPLAY 1.021277 (3700 3325);
DISPLAY INVISIBLE (3700 3325);
FORCEADD OFFPAGE..2
R 2
(-1250 1000);
FORCEPROP 2 LAST $XR0 30 
J 0
(-1504 1000);
DISPLAY 0.638298 (-1504 1000);
PAINT MONO (-1504 1000);
FORCEPROP 2 LAST CDS_LIB standard
J 0
(-1250 1000);
DISPLAY INVISIBLE (-1250 1000);
FORCEPROP 1 LAST OFFPAGE TRUE
J 2
(-1575 875);
DISPLAY 0.872340 (-1575 875);
PAINT AQUA (-1575 875);
DISPLAY INVISIBLE (-1575 875);
FORCEPROP 1 LAST COMMENT_BODY TRUE
J 2
(-1205 905);
DISPLAY 0.872340 (-1205 905);
PAINT GREEN (-1205 905);
DISPLAY INVISIBLE (-1205 905);
FORCEPROP 2 LAST PATH I6
J 0
(-1200 1075);
DISPLAY 1.021277 (-1200 1075);
DISPLAY INVISIBLE (-1200 1075);
FORCEADD OFFPAGE..1
(3650 3300);
FORCEPROP 2 LAST $XR0 174 
J 0
(3368 3300);
DISPLAY 0.638298 (3368 3300);
PAINT MONO (3368 3300);
FORCEPROP 2 LAST CDS_LIB standard
J 0
(3650 3300);
DISPLAY INVISIBLE (3650 3300);
FORCEPROP 1 LAST OFFPAGE TRUE
J 0
(3975 3175);
DISPLAY 0.872340 (3975 3175);
PAINT AQUA (3975 3175);
DISPLAY INVISIBLE (3975 3175);
FORCEPROP 1 LAST COMMENT_BODY TRUE
J 0
(3775 3200);
DISPLAY 0.872340 (3775 3200);
PAINT GREEN (3775 3200);
DISPLAY INVISIBLE (3775 3200);
FORCEPROP 2 LAST PATH I60
J 0
(3700 3375);
DISPLAY 1.021277 (3700 3375);
DISPLAY INVISIBLE (3700 3375);
FORCEADD OFFPAGE..5
(3650 3400);
FORCEPROP 2 LAST $XR0 30 
J 0
(3426 3400);
DISPLAY 0.638298 (3426 3400);
PAINT MONO (3426 3400);
FORCEPROP 2 LAST CDS_LIB standard
J 0
(3650 3400);
DISPLAY INVISIBLE (3650 3400);
FORCEPROP 1 LAST OFFPAGE TRUE
J 0
(3975 3275);
DISPLAY 0.872340 (3975 3275);
PAINT AQUA (3975 3275);
DISPLAY INVISIBLE (3975 3275);
FORCEPROP 1 LAST COMMENT_BODY TRUE
J 0
(3750 3325);
DISPLAY 1.170213 (3750 3325);
PAINT GREEN (3750 3325);
DISPLAY INVISIBLE (3750 3325);
FORCEPROP 2 LAST PATH I61
J 0
(3700 3475);
DISPLAY 1.021277 (3700 3475);
DISPLAY INVISIBLE (3700 3475);
FORCEADD OFFPAGE..2
R 2
(3650 3450);
FORCEPROP 2 LAST $XR0 30 
J 0
(3426 3450);
DISPLAY 0.638298 (3426 3450);
PAINT MONO (3426 3450);
FORCEPROP 2 LAST CDS_LIB standard
J 0
(3650 3450);
DISPLAY INVISIBLE (3650 3450);
FORCEPROP 1 LAST OFFPAGE TRUE
J 2
(3325 3325);
DISPLAY 0.872340 (3325 3325);
PAINT AQUA (3325 3325);
DISPLAY INVISIBLE (3325 3325);
FORCEPROP 1 LAST COMMENT_BODY TRUE
J 2
(3695 3355);
DISPLAY 0.872340 (3695 3355);
PAINT GREEN (3695 3355);
DISPLAY INVISIBLE (3695 3355);
FORCEPROP 2 LAST PATH I62
J 0
(3700 3525);
DISPLAY 1.021277 (3700 3525);
DISPLAY INVISIBLE (3700 3525);
FORCEADD OFFPAGE..2
R 2
(3650 3600);
FORCEPROP 2 LAST $XR0 30 
J 0
(3426 3600);
DISPLAY 0.638298 (3426 3600);
PAINT MONO (3426 3600);
FORCEPROP 2 LAST CDS_LIB standard
J 0
(3650 3600);
DISPLAY INVISIBLE (3650 3600);
FORCEPROP 1 LAST COMMENT_BODY TRUE
J 2
(3695 3505);
DISPLAY 0.872340 (3695 3505);
PAINT GREEN (3695 3505);
DISPLAY INVISIBLE (3695 3505);
FORCEPROP 1 LAST OFFPAGE TRUE
J 2
(3325 3475);
DISPLAY 0.872340 (3325 3475);
PAINT AQUA (3325 3475);
DISPLAY INVISIBLE (3325 3475);
FORCEPROP 2 LAST PATH I63
J 0
(3700 3675);
DISPLAY 1.021277 (3700 3675);
DISPLAY INVISIBLE (3700 3675);
FORCEADD OFFPAGE..5
(3650 3550);
FORCEPROP 2 LAST $XR0 30 
J 0
(3426 3550);
DISPLAY 0.638298 (3426 3550);
PAINT MONO (3426 3550);
FORCEPROP 2 LAST CDS_LIB standard
J 0
(3650 3550);
DISPLAY INVISIBLE (3650 3550);
FORCEPROP 1 LAST COMMENT_BODY TRUE
J 0
(3750 3475);
DISPLAY 1.170213 (3750 3475);
PAINT GREEN (3750 3475);
DISPLAY INVISIBLE (3750 3475);
FORCEPROP 1 LAST OFFPAGE TRUE
J 0
(3975 3425);
DISPLAY 0.872340 (3975 3425);
PAINT AQUA (3975 3425);
DISPLAY INVISIBLE (3975 3425);
FORCEPROP 2 LAST PATH I64
J 0
(3700 3625);
DISPLAY 1.021277 (3700 3625);
DISPLAY INVISIBLE (3700 3625);
FORCEADD CONN112_10137002101LF..2
(5875 2150);
FORCEPROP 1 LAST PART_NUMBER DFHSB2FR012
J 0
(5125 3925);
DISPLAY 0.723404 (5125 3925);
PAINT GREEN (5125 3925);
DISPLAY INVISIBLE (5125 3925);
FORCEPROP 2 LAST PART_TYPE THLF
J 0
(5125 4050);
DISPLAY 1.021277 (5125 4050);
FORCEPROP 1 LAST MATERIAL IO
J 0
(5133 3863);
DISPLAY 0.723404 (5133 3863);
PAINT GREEN (5133 3863);
FORCEPROP 1 LAST LOCATION J105
J 0
(5125 3975);
DISPLAY 0.723404 (5125 3975);
PAINT GREEN (5125 3975);
FORCEPROP 0 LASTPIN (4950 1250) $PN A1
J 2
(4940 1260);
DISPLAY 0.680851 (4940 1260);
PAINT MONO (4940 1260);
FORCEPROP 0 LASTPIN (4950 2050) $PN A2
J 2
(4940 2060);
DISPLAY 0.680851 (4940 2060);
PAINT MONO (4940 2060);
FORCEPROP 0 LASTPIN (4950 2850) $PN A3
J 2
(4940 2860);
DISPLAY 0.680851 (4940 2860);
PAINT MONO (4940 2860);
FORCEPROP 0 LASTPIN (4950 3650) $PN A4
J 2
(4940 3660);
DISPLAY 0.680851 (4940 3660);
PAINT MONO (4940 3660);
FORCEPROP 0 LASTPIN (4950 1200) $PN B1
J 2
(4940 1210);
DISPLAY 0.680851 (4940 1210);
PAINT MONO (4940 1210);
FORCEPROP 0 LASTPIN (4950 2000) $PN B2
J 2
(4940 2010);
DISPLAY 0.680851 (4940 2010);
PAINT MONO (4940 2010);
FORCEPROP 0 LASTPIN (4950 2800) $PN B3
J 2
(4940 2810);
DISPLAY 0.680851 (4940 2810);
PAINT MONO (4940 2810);
FORCEPROP 0 LASTPIN (4950 3600) $PN B4
J 2
(4940 3610);
DISPLAY 0.680851 (4940 3610);
PAINT MONO (4940 3610);
FORCEPROP 0 LASTPIN (4950 1150) $PN C1
J 2
(4940 1160);
DISPLAY 0.680851 (4940 1160);
PAINT MONO (4940 1160);
FORCEPROP 0 LASTPIN (4950 1950) $PN C2
J 2
(4940 1960);
DISPLAY 0.680851 (4940 1960);
PAINT MONO (4940 1960);
FORCEPROP 0 LASTPIN (4950 2750) $PN C3
J 2
(4940 2760);
DISPLAY 0.680851 (4940 2760);
PAINT MONO (4940 2760);
FORCEPROP 0 LASTPIN (4950 3550) $PN C4
J 2
(4940 3560);
DISPLAY 0.680851 (4940 3560);
PAINT MONO (4940 3560);
FORCEPROP 0 LASTPIN (4950 1100) $PN D1
J 2
(4940 1110);
DISPLAY 0.680851 (4940 1110);
PAINT MONO (4940 1110);
FORCEPROP 0 LASTPIN (4950 1900) $PN D2
J 2
(4940 1910);
DISPLAY 0.680851 (4940 1910);
PAINT MONO (4940 1910);
FORCEPROP 0 LASTPIN (4950 2700) $PN D3
J 2
(4940 2710);
DISPLAY 0.680851 (4940 2710);
PAINT MONO (4940 2710);
FORCEPROP 0 LASTPIN (4950 3500) $PN D4
J 2
(4940 3510);
DISPLAY 0.680851 (4940 3510);
PAINT MONO (4940 3510);
FORCEPROP 0 LASTPIN (4950 1050) $PN E1
J 2
(4940 1060);
DISPLAY 0.680851 (4940 1060);
PAINT MONO (4940 1060);
FORCEPROP 0 LASTPIN (4950 1850) $PN E2
J 2
(4940 1860);
DISPLAY 0.680851 (4940 1860);
PAINT MONO (4940 1860);
FORCEPROP 0 LASTPIN (4950 2650) $PN E3
J 2
(4940 2660);
DISPLAY 0.680851 (4940 2660);
PAINT MONO (4940 2660);
FORCEPROP 0 LASTPIN (4950 3450) $PN E4
J 2
(4940 3460);
DISPLAY 0.680851 (4940 3460);
PAINT MONO (4940 3460);
FORCEPROP 0 LASTPIN (4950 1000) $PN F1
J 2
(4940 1010);
DISPLAY 0.680851 (4940 1010);
PAINT MONO (4940 1010);
FORCEPROP 0 LASTPIN (4950 1800) $PN F2
J 2
(4940 1810);
DISPLAY 0.680851 (4940 1810);
PAINT MONO (4940 1810);
FORCEPROP 0 LASTPIN (4950 2600) $PN F3
J 2
(4940 2610);
DISPLAY 0.680851 (4940 2610);
PAINT MONO (4940 2610);
FORCEPROP 0 LASTPIN (4950 3400) $PN F4
J 2
(4940 3410);
DISPLAY 0.680851 (4940 3410);
PAINT MONO (4940 3410);
FORCEPROP 0 LASTPIN (4950 950) $PN G1
J 2
(4940 960);
DISPLAY 0.680851 (4940 960);
PAINT MONO (4940 960);
FORCEPROP 0 LASTPIN (4950 1750) $PN G2
J 2
(4940 1760);
DISPLAY 0.680851 (4940 1760);
PAINT MONO (4940 1760);
FORCEPROP 0 LASTPIN (4950 2550) $PN G3
J 2
(4940 2560);
DISPLAY 0.680851 (4940 2560);
PAINT MONO (4940 2560);
FORCEPROP 0 LASTPIN (4950 3350) $PN G4
J 2
(4940 3360);
DISPLAY 0.680851 (4940 3360);
PAINT MONO (4940 3360);
FORCEPROP 0 LASTPIN (4950 900) $PN H1
J 2
(4940 910);
DISPLAY 0.680851 (4940 910);
PAINT MONO (4940 910);
FORCEPROP 0 LASTPIN (4950 1700) $PN H2
J 2
(4940 1710);
DISPLAY 0.680851 (4940 1710);
PAINT MONO (4940 1710);
FORCEPROP 0 LASTPIN (4950 2500) $PN H3
J 2
(4940 2510);
DISPLAY 0.680851 (4940 2510);
PAINT MONO (4940 2510);
FORCEPROP 0 LASTPIN (4950 3300) $PN H4
J 2
(4940 3310);
DISPLAY 0.680851 (4940 3310);
PAINT MONO (4940 3310);
FORCEPROP 0 LASTPIN (4950 850) $PN I1
J 2
(4940 860);
DISPLAY 0.680851 (4940 860);
PAINT MONO (4940 860);
FORCEPROP 0 LASTPIN (4950 1650) $PN I2
J 2
(4940 1660);
DISPLAY 0.680851 (4940 1660);
PAINT MONO (4940 1660);
FORCEPROP 0 LASTPIN (4950 2450) $PN I3
J 2
(4940 2460);
DISPLAY 0.680851 (4940 2460);
PAINT MONO (4940 2460);
FORCEPROP 0 LASTPIN (4950 3250) $PN I4
J 2
(4940 3260);
DISPLAY 0.680851 (4940 3260);
PAINT MONO (4940 3260);
FORCEPROP 0 LASTPIN (4950 800) $PN J1
J 2
(4940 810);
DISPLAY 0.680851 (4940 810);
PAINT MONO (4940 810);
FORCEPROP 0 LASTPIN (4950 1600) $PN J2
J 2
(4940 1610);
DISPLAY 0.680851 (4940 1610);
PAINT MONO (4940 1610);
FORCEPROP 0 LASTPIN (4950 2400) $PN J3
J 2
(4940 2410);
DISPLAY 0.680851 (4940 2410);
PAINT MONO (4940 2410);
FORCEPROP 0 LASTPIN (4950 3200) $PN J4
J 2
(4940 3210);
DISPLAY 0.680851 (4940 3210);
PAINT MONO (4940 3210);
FORCEPROP 0 LASTPIN (4950 750) $PN K1
J 2
(4940 760);
DISPLAY 0.680851 (4940 760);
PAINT MONO (4940 760);
FORCEPROP 0 LASTPIN (4950 1550) $PN K2
J 2
(4940 1560);
DISPLAY 0.680851 (4940 1560);
PAINT MONO (4940 1560);
FORCEPROP 0 LASTPIN (4950 2350) $PN K3
J 2
(4940 2360);
DISPLAY 0.680851 (4940 2360);
PAINT MONO (4940 2360);
FORCEPROP 0 LASTPIN (4950 3150) $PN K4
J 2
(4940 3160);
DISPLAY 0.680851 (4940 3160);
PAINT MONO (4940 3160);
FORCEPROP 0 LASTPIN (4950 700) $PN L1
J 2
(4940 710);
DISPLAY 0.680851 (4940 710);
PAINT MONO (4940 710);
FORCEPROP 0 LASTPIN (4950 1500) $PN L2
J 2
(4940 1510);
DISPLAY 0.680851 (4940 1510);
PAINT MONO (4940 1510);
FORCEPROP 0 LASTPIN (4950 2300) $PN L3
J 2
(4940 2310);
DISPLAY 0.680851 (4940 2310);
PAINT MONO (4940 2310);
FORCEPROP 0 LASTPIN (4950 3100) $PN L4
J 2
(4940 3110);
DISPLAY 0.680851 (4940 3110);
PAINT MONO (4940 3110);
FORCEPROP 0 LASTPIN (4950 650) $PN M1
J 2
(4940 660);
DISPLAY 0.680851 (4940 660);
PAINT MONO (4940 660);
FORCEPROP 0 LASTPIN (4950 1450) $PN M2
J 2
(4940 1460);
DISPLAY 0.680851 (4940 1460);
PAINT MONO (4940 1460);
FORCEPROP 0 LASTPIN (4950 2250) $PN M3
J 2
(4940 2260);
DISPLAY 0.680851 (4940 2260);
PAINT MONO (4940 2260);
FORCEPROP 0 LASTPIN (4950 3050) $PN M4
J 2
(4940 3060);
DISPLAY 0.680851 (4940 3060);
PAINT MONO (4940 3060);
FORCEPROP 0 LASTPIN (4950 600) $PN N1
J 2
(4940 610);
DISPLAY 0.680851 (4940 610);
PAINT MONO (4940 610);
FORCEPROP 0 LASTPIN (4950 1400) $PN N2
J 2
(4940 1410);
DISPLAY 0.680851 (4940 1410);
PAINT MONO (4940 1410);
FORCEPROP 0 LASTPIN (4950 2200) $PN N3
J 2
(4940 2210);
DISPLAY 0.680851 (4940 2210);
PAINT MONO (4940 2210);
FORCEPROP 0 LASTPIN (4950 3000) $PN N4
J 2
(4940 3010);
DISPLAY 0.680851 (4940 3010);
PAINT MONO (4940 3010);
FORCEPROP 2 LAST CDS_LIB pure_quanta
J 0
(5875 2150);
DISPLAY INVISIBLE (5875 2150);
FORCEPROP 1 LAST CDS_LMAN_SYM_OUTLINE -775,1650,775,-1650
J 0
(5875 2150);
DISPLAY 0.468085 (5875 2150);
PAINT GREEN (5875 2150);
DISPLAY INVISIBLE (5875 2150);
FORCEPROP 0 LAST VALUE CONN112_10137002-101LF
J 0
(5125 4050);
DISPLAY 1.021277 (5125 4050);
DISPLAY INVISIBLE (5125 4050);
FORCEPROP 1 LAST NEEDS_NO_SIZE TRUE
J 0
(5875 2150);
DISPLAY 0.723404 (5875 2150);
PAINT GREEN (5875 2150);
DISPLAY INVISIBLE (5875 2150);
FORCEPROP 1 LAST PATH I65
J 0
(5875 2150);
DISPLAY 0.723404 (5875 2150);
PAINT GREEN (5875 2150);
DISPLAY INVISIBLE (5875 2150);
FORCEPROP 0 LAST $SEC 2
J 0
(5125 4100);
DISPLAY 0.680851 (5125 4100);
PAINT MONO (5125 4100);
DISPLAY INVISIBLE (5125 4100);
FORCEPROP 0 LAST CDS_SEC 2
J 0
(5125 4100);
DISPLAY 1.021277 (5125 4100);
DISPLAY INVISIBLE (5125 4100);
FORCEADD OFFPAGE..1
(3675 1500);
FORCEPROP 2 LAST $XR0 173 
J 0
(3423 1500);
DISPLAY 0.638298 (3423 1500);
PAINT MONO (3423 1500);
FORCEPROP 2 LAST CDS_LIB standard
J 0
(3675 1500);
DISPLAY INVISIBLE (3675 1500);
FORCEPROP 1 LAST OFFPAGE TRUE
J 0
(4000 1375);
DISPLAY 0.872340 (4000 1375);
PAINT AQUA (4000 1375);
DISPLAY INVISIBLE (4000 1375);
FORCEPROP 1 LAST COMMENT_BODY TRUE
J 0
(3800 1400);
DISPLAY 0.872340 (3800 1400);
PAINT GREEN (3800 1400);
DISPLAY INVISIBLE (3800 1400);
FORCEPROP 2 LAST PATH I66
J 0
(3725 1575);
DISPLAY 1.021277 (3725 1575);
DISPLAY INVISIBLE (3725 1575);
FORCEADD OFFPAGE..1
(3675 1550);
FORCEPROP 2 LAST $XR0 173 
J 0
(3423 1550);
DISPLAY 0.638298 (3423 1550);
PAINT MONO (3423 1550);
FORCEPROP 2 LAST CDS_LIB standard
J 0
(3675 1550);
DISPLAY INVISIBLE (3675 1550);
FORCEPROP 1 LAST OFFPAGE TRUE
J 0
(4000 1425);
DISPLAY 0.872340 (4000 1425);
PAINT AQUA (4000 1425);
DISPLAY INVISIBLE (4000 1425);
FORCEPROP 1 LAST COMMENT_BODY TRUE
J 0
(3800 1450);
DISPLAY 0.872340 (3800 1450);
PAINT GREEN (3800 1450);
DISPLAY INVISIBLE (3800 1450);
FORCEPROP 2 LAST PATH I67
J 0
(3725 1625);
DISPLAY 1.021277 (3725 1625);
DISPLAY INVISIBLE (3725 1625);
FORCEADD CONN112_10137002101LF..1
(950 2150);
FORCEPROP 1 LAST PART_NUMBER DFHSB2FR012
J 0
(200 3900);
DISPLAY 0.723404 (200 3900);
PAINT GREEN (200 3900);
DISPLAY INVISIBLE (200 3900);
FORCEPROP 2 LAST PART_TYPE THLF
J 0
(200 4025);
DISPLAY 1.021277 (200 4025);
FORCEPROP 1 LAST MATERIAL IO
J 0
(205 3832);
DISPLAY 0.723404 (205 3832);
PAINT GREEN (205 3832);
FORCEPROP 1 LAST LOCATION J105
J 0
(200 3950);
DISPLAY 0.723404 (200 3950);
PAINT GREEN (200 3950);
FORCEPROP 0 LASTPIN (25 1250) $PN A5
J 2
(15 1260);
DISPLAY 0.680851 (15 1260);
PAINT MONO (15 1260);
FORCEPROP 0 LASTPIN (25 2050) $PN A6
J 2
(15 2060);
DISPLAY 0.680851 (15 2060);
PAINT MONO (15 2060);
FORCEPROP 0 LASTPIN (25 2850) $PN A7
J 2
(15 2860);
DISPLAY 0.680851 (15 2860);
PAINT MONO (15 2860);
FORCEPROP 0 LASTPIN (25 3650) $PN A8
J 2
(15 3660);
DISPLAY 0.680851 (15 3660);
PAINT MONO (15 3660);
FORCEPROP 0 LASTPIN (25 1200) $PN B5
J 2
(15 1210);
DISPLAY 0.680851 (15 1210);
PAINT MONO (15 1210);
FORCEPROP 0 LASTPIN (25 2000) $PN B6
J 2
(15 2010);
DISPLAY 0.680851 (15 2010);
PAINT MONO (15 2010);
FORCEPROP 0 LASTPIN (25 2800) $PN B7
J 2
(15 2810);
DISPLAY 0.680851 (15 2810);
PAINT MONO (15 2810);
FORCEPROP 0 LASTPIN (25 3600) $PN B8
J 2
(15 3610);
DISPLAY 0.680851 (15 3610);
PAINT MONO (15 3610);
FORCEPROP 0 LASTPIN (25 1150) $PN C5
J 2
(15 1160);
DISPLAY 0.680851 (15 1160);
PAINT MONO (15 1160);
FORCEPROP 0 LASTPIN (25 1950) $PN C6
J 2
(15 1960);
DISPLAY 0.680851 (15 1960);
PAINT MONO (15 1960);
FORCEPROP 0 LASTPIN (25 2750) $PN C7
J 2
(15 2760);
DISPLAY 0.680851 (15 2760);
PAINT MONO (15 2760);
FORCEPROP 0 LASTPIN (25 3550) $PN C8
J 2
(15 3560);
DISPLAY 0.680851 (15 3560);
PAINT MONO (15 3560);
FORCEPROP 0 LASTPIN (25 1100) $PN D5
J 2
(15 1110);
DISPLAY 0.680851 (15 1110);
PAINT MONO (15 1110);
FORCEPROP 0 LASTPIN (25 1900) $PN D6
J 2
(15 1910);
DISPLAY 0.680851 (15 1910);
PAINT MONO (15 1910);
FORCEPROP 0 LASTPIN (25 2700) $PN D7
J 2
(15 2710);
DISPLAY 0.680851 (15 2710);
PAINT MONO (15 2710);
FORCEPROP 0 LASTPIN (25 3500) $PN D8
J 2
(15 3510);
DISPLAY 0.680851 (15 3510);
PAINT MONO (15 3510);
FORCEPROP 0 LASTPIN (25 1050) $PN E5
J 2
(15 1060);
DISPLAY 0.680851 (15 1060);
PAINT MONO (15 1060);
FORCEPROP 0 LASTPIN (25 1850) $PN E6
J 2
(15 1860);
DISPLAY 0.680851 (15 1860);
PAINT MONO (15 1860);
FORCEPROP 0 LASTPIN (25 2650) $PN E7
J 2
(15 2660);
DISPLAY 0.680851 (15 2660);
PAINT MONO (15 2660);
FORCEPROP 0 LASTPIN (25 3450) $PN E8
J 2
(15 3460);
DISPLAY 0.680851 (15 3460);
PAINT MONO (15 3460);
FORCEPROP 0 LASTPIN (25 1000) $PN F5
J 2
(15 1010);
DISPLAY 0.680851 (15 1010);
PAINT MONO (15 1010);
FORCEPROP 0 LASTPIN (25 1800) $PN F6
J 2
(15 1810);
DISPLAY 0.680851 (15 1810);
PAINT MONO (15 1810);
FORCEPROP 0 LASTPIN (25 2600) $PN F7
J 2
(15 2610);
DISPLAY 0.680851 (15 2610);
PAINT MONO (15 2610);
FORCEPROP 0 LASTPIN (25 3400) $PN F8
J 2
(15 3410);
DISPLAY 0.680851 (15 3410);
PAINT MONO (15 3410);
FORCEPROP 0 LASTPIN (25 950) $PN G5
J 2
(15 960);
DISPLAY 0.680851 (15 960);
PAINT MONO (15 960);
FORCEPROP 0 LASTPIN (25 1750) $PN G6
J 2
(15 1760);
DISPLAY 0.680851 (15 1760);
PAINT MONO (15 1760);
FORCEPROP 0 LASTPIN (25 2550) $PN G7
J 2
(15 2560);
DISPLAY 0.680851 (15 2560);
PAINT MONO (15 2560);
FORCEPROP 0 LASTPIN (25 3350) $PN G8
J 2
(15 3360);
DISPLAY 0.680851 (15 3360);
PAINT MONO (15 3360);
FORCEPROP 0 LASTPIN (25 900) $PN H5
J 2
(15 910);
DISPLAY 0.680851 (15 910);
PAINT MONO (15 910);
FORCEPROP 0 LASTPIN (25 1700) $PN H6
J 2
(15 1710);
DISPLAY 0.680851 (15 1710);
PAINT MONO (15 1710);
FORCEPROP 0 LASTPIN (25 2500) $PN H7
J 2
(15 2510);
DISPLAY 0.680851 (15 2510);
PAINT MONO (15 2510);
FORCEPROP 0 LASTPIN (25 3300) $PN H8
J 2
(15 3310);
DISPLAY 0.680851 (15 3310);
PAINT MONO (15 3310);
FORCEPROP 0 LASTPIN (25 850) $PN I5
J 2
(15 860);
DISPLAY 0.680851 (15 860);
PAINT MONO (15 860);
FORCEPROP 0 LASTPIN (25 1650) $PN I6
J 2
(15 1660);
DISPLAY 0.680851 (15 1660);
PAINT MONO (15 1660);
FORCEPROP 0 LASTPIN (25 2450) $PN I7
J 2
(15 2460);
DISPLAY 0.680851 (15 2460);
PAINT MONO (15 2460);
FORCEPROP 0 LASTPIN (25 3250) $PN I8
J 2
(15 3260);
DISPLAY 0.680851 (15 3260);
PAINT MONO (15 3260);
FORCEPROP 0 LASTPIN (25 800) $PN J5
J 2
(15 810);
DISPLAY 0.680851 (15 810);
PAINT MONO (15 810);
FORCEPROP 0 LASTPIN (25 1600) $PN J6
J 2
(15 1610);
DISPLAY 0.680851 (15 1610);
PAINT MONO (15 1610);
FORCEPROP 0 LASTPIN (25 2400) $PN J7
J 2
(15 2410);
DISPLAY 0.680851 (15 2410);
PAINT MONO (15 2410);
FORCEPROP 0 LASTPIN (25 3200) $PN J8
J 2
(15 3210);
DISPLAY 0.680851 (15 3210);
PAINT MONO (15 3210);
FORCEPROP 0 LASTPIN (25 750) $PN K5
J 2
(15 760);
DISPLAY 0.680851 (15 760);
PAINT MONO (15 760);
FORCEPROP 0 LASTPIN (25 1550) $PN K6
J 2
(15 1560);
DISPLAY 0.680851 (15 1560);
PAINT MONO (15 1560);
FORCEPROP 0 LASTPIN (25 2350) $PN K7
J 2
(15 2360);
DISPLAY 0.680851 (15 2360);
PAINT MONO (15 2360);
FORCEPROP 0 LASTPIN (25 3150) $PN K8
J 2
(15 3160);
DISPLAY 0.680851 (15 3160);
PAINT MONO (15 3160);
FORCEPROP 0 LASTPIN (25 700) $PN L5
J 2
(15 710);
DISPLAY 0.680851 (15 710);
PAINT MONO (15 710);
FORCEPROP 0 LASTPIN (25 1500) $PN L6
J 2
(15 1510);
DISPLAY 0.680851 (15 1510);
PAINT MONO (15 1510);
FORCEPROP 0 LASTPIN (25 2300) $PN L7
J 2
(15 2310);
DISPLAY 0.680851 (15 2310);
PAINT MONO (15 2310);
FORCEPROP 0 LASTPIN (25 3100) $PN L8
J 2
(15 3110);
DISPLAY 0.680851 (15 3110);
PAINT MONO (15 3110);
FORCEPROP 0 LASTPIN (25 650) $PN M5
J 2
(15 660);
DISPLAY 0.680851 (15 660);
PAINT MONO (15 660);
FORCEPROP 0 LASTPIN (25 1450) $PN M6
J 2
(15 1460);
DISPLAY 0.680851 (15 1460);
PAINT MONO (15 1460);
FORCEPROP 0 LASTPIN (25 2250) $PN M7
J 2
(15 2260);
DISPLAY 0.680851 (15 2260);
PAINT MONO (15 2260);
FORCEPROP 0 LASTPIN (25 3050) $PN M8
J 2
(15 3060);
DISPLAY 0.680851 (15 3060);
PAINT MONO (15 3060);
FORCEPROP 0 LASTPIN (25 600) $PN N5
J 2
(15 610);
DISPLAY 0.680851 (15 610);
PAINT MONO (15 610);
FORCEPROP 0 LASTPIN (25 1400) $PN N6
J 2
(15 1410);
DISPLAY 0.680851 (15 1410);
PAINT MONO (15 1410);
FORCEPROP 0 LASTPIN (25 2200) $PN N7
J 2
(15 2210);
DISPLAY 0.680851 (15 2210);
PAINT MONO (15 2210);
FORCEPROP 0 LASTPIN (25 3000) $PN N8
J 2
(15 3010);
DISPLAY 0.680851 (15 3010);
PAINT MONO (15 3010);
FORCEPROP 2 LAST CDS_LIB pure_quanta
J 0
(950 2150);
DISPLAY INVISIBLE (950 2150);
FORCEPROP 1 LAST CDS_LMAN_SYM_OUTLINE -775,1650,775,-1650
J 0
(950 2150);
DISPLAY 0.468085 (950 2150);
PAINT GREEN (950 2150);
DISPLAY INVISIBLE (950 2150);
FORCEPROP 1 LAST NEEDS_NO_SIZE TRUE
J 0
(950 2150);
DISPLAY 0.723404 (950 2150);
PAINT GREEN (950 2150);
DISPLAY INVISIBLE (950 2150);
FORCEPROP 0 LAST VALUE CONN112_10137002-101LF
J 0
(225 4150);
DISPLAY 1.021277 (225 4150);
DISPLAY INVISIBLE (225 4150);
FORCEPROP 1 LAST PATH I68
J 0
(950 2150);
DISPLAY 0.723404 (950 2150);
PAINT GREEN (950 2150);
DISPLAY INVISIBLE (950 2150);
FORCEPROP 0 LAST $SEC 1
J 0
(200 4075);
DISPLAY 0.680851 (200 4075);
PAINT MONO (200 4075);
DISPLAY INVISIBLE (200 4075);
FORCEPROP 0 LAST CDS_SEC 1
J 0
(200 4075);
DISPLAY 1.021277 (200 4075);
DISPLAY INVISIBLE (200 4075);
FORCEADD OFFPAGE..5
(-1250 950);
FORCEPROP 2 LAST $XR0 30 
J 0
(-1504 950);
DISPLAY 0.638298 (-1504 950);
PAINT MONO (-1504 950);
FORCEPROP 2 LAST CDS_LIB standard
J 0
(-1250 950);
DISPLAY INVISIBLE (-1250 950);
FORCEPROP 1 LAST OFFPAGE TRUE
J 0
(-925 825);
DISPLAY 0.872340 (-925 825);
PAINT AQUA (-925 825);
DISPLAY INVISIBLE (-925 825);
FORCEPROP 1 LAST COMMENT_BODY TRUE
J 0
(-1150 875);
DISPLAY 1.170213 (-1150 875);
PAINT GREEN (-1150 875);
DISPLAY INVISIBLE (-1150 875);
FORCEPROP 2 LAST PATH I7
J 0
(-1200 1025);
DISPLAY 1.021277 (-1200 1025);
DISPLAY INVISIBLE (-1200 1025);
FORCEADD OFFPAGE..5
(-1250 1100);
FORCEPROP 2 LAST $XR0 30 
J 0
(-1504 1100);
DISPLAY 0.638298 (-1504 1100);
PAINT MONO (-1504 1100);
FORCEPROP 2 LAST CDS_LIB standard
J 0
(-1250 1100);
DISPLAY INVISIBLE (-1250 1100);
FORCEPROP 1 LAST OFFPAGE TRUE
J 0
(-925 975);
DISPLAY 0.872340 (-925 975);
PAINT AQUA (-925 975);
DISPLAY INVISIBLE (-925 975);
FORCEPROP 1 LAST COMMENT_BODY TRUE
J 0
(-1150 1025);
DISPLAY 1.170213 (-1150 1025);
PAINT GREEN (-1150 1025);
DISPLAY INVISIBLE (-1150 1025);
FORCEPROP 2 LAST PATH I8
J 0
(-1200 1175);
DISPLAY 1.021277 (-1200 1175);
DISPLAY INVISIBLE (-1200 1175);
FORCEADD OFFPAGE..4
R 2
(3675 1400);
FORCEPROP 2 LAST $XR0 149 
J 0
(3423 1400);
DISPLAY 0.638298 (3423 1400);
PAINT MONO (3423 1400);
FORCEPROP 2 LAST CDS_LIB standard
J 0
(3675 1400);
DISPLAY INVISIBLE (3675 1400);
FORCEPROP 1 LAST OFFPAGE TRUE
J 2
(3350 1275);
DISPLAY 0.872340 (3350 1275);
PAINT GREEN (3350 1275);
DISPLAY INVISIBLE (3350 1275);
FORCEPROP 1 LAST COMMENT_BODY TRUE
J 2
(3700 1300);
DISPLAY 0.872340 (3700 1300);
PAINT GREEN (3700 1300);
DISPLAY INVISIBLE (3700 1300);
FORCEPROP 2 LAST PATH I80
J 0
(3425 1450);
DISPLAY 1.021277 (3425 1450);
DISPLAY INVISIBLE (3425 1450);
FORCEADD OFFPAGE..5
(-1250 3000);
FORCEPROP 2 LAST $XR0 148 
J 0
(-1535 3000);
DISPLAY 0.638298 (-1535 3000);
PAINT MONO (-1535 3000);
FORCEPROP 2 LAST CDS_LIB standard
J 0
(-1250 3000);
DISPLAY INVISIBLE (-1250 3000);
FORCEPROP 1 LAST COMMENT_BODY TRUE
J 0
(-1150 2925);
DISPLAY 1.170213 (-1150 2925);
PAINT GREEN (-1150 2925);
DISPLAY INVISIBLE (-1150 2925);
FORCEPROP 1 LAST OFFPAGE TRUE
J 0
(-925 2875);
DISPLAY 0.872340 (-925 2875);
PAINT AQUA (-925 2875);
DISPLAY INVISIBLE (-925 2875);
FORCEPROP 2 LAST PATH I83
J 0
(-1200 3075);
DISPLAY 1.021277 (-1200 3075);
DISPLAY INVISIBLE (-1200 3075);
FORCEADD OFFPAGE..4
R 2
(-1250 1400);
FORCEPROP 2 LAST $XR0 151 
J 0
(-1502 1400);
DISPLAY 0.638298 (-1502 1400);
PAINT MONO (-1502 1400);
FORCEPROP 2 LAST PATH I84
J 0
(-1500 1450);
DISPLAY 1.021277 (-1500 1450);
DISPLAY INVISIBLE (-1500 1450);
FORCEPROP 2 LAST CDS_LIB standard
J 0
(-1250 1400);
DISPLAY INVISIBLE (-1250 1400);
FORCEPROP 1 LAST COMMENT_BODY TRUE
J 2
(-1225 1300);
DISPLAY 0.872340 (-1225 1300);
PAINT GREEN (-1225 1300);
DISPLAY INVISIBLE (-1225 1300);
FORCEPROP 1 LAST OFFPAGE TRUE
J 2
(-1575 1275);
DISPLAY 0.872340 (-1575 1275);
PAINT GREEN (-1575 1275);
DISPLAY INVISIBLE (-1575 1275);
FORCEADD OFFPAGE..5
(3650 3000);
FORCEPROP 2 LAST $XR0 148 
J 0
(3395 3000);
DISPLAY 0.638298 (3395 3000);
PAINT MONO (3395 3000);
FORCEPROP 2 LAST CDS_LIB standard
J 0
(3650 3000);
DISPLAY INVISIBLE (3650 3000);
FORCEPROP 1 LAST COMMENT_BODY TRUE
J 0
(3750 2925);
DISPLAY 1.170213 (3750 2925);
PAINT GREEN (3750 2925);
DISPLAY INVISIBLE (3750 2925);
FORCEPROP 1 LAST OFFPAGE TRUE
J 0
(3975 2875);
DISPLAY 0.872340 (3975 2875);
PAINT AQUA (3975 2875);
DISPLAY INVISIBLE (3975 2875);
FORCEPROP 2 LAST PATH I85
J 0
(3375 3050);
DISPLAY 1.021277 (3375 3050);
DISPLAY INVISIBLE (3375 3050);
FORCEADD OFFPAGE..1
(3650 2850);
FORCEPROP 2 LAST $XR0 147 
J 0
(3368 2850);
DISPLAY 0.638298 (3368 2850);
PAINT MONO (3368 2850);
FORCEPROP 2 LAST CDS_LIB standard
J 0
(3650 2850);
DISPLAY INVISIBLE (3650 2850);
FORCEPROP 2 LAST PATH I86
J 0
(3700 2925);
DISPLAY 1.021277 (3700 2925);
DISPLAY INVISIBLE (3700 2925);
FORCEPROP 1 LAST OFFPAGE TRUE
J 0
(3975 2725);
DISPLAY 0.872340 (3975 2725);
PAINT AQUA (3975 2725);
DISPLAY INVISIBLE (3975 2725);
FORCEPROP 1 LAST COMMENT_BODY TRUE
J 0
(3775 2750);
DISPLAY 0.872340 (3775 2750);
PAINT GREEN (3775 2750);
DISPLAY INVISIBLE (3775 2750);
FORCEADD OFFPAGE..2
R 2
(3675 1250);
FORCEPROP 2 LAST $XR0 145 
J 0
(3420 1250);
DISPLAY 0.638298 (3420 1250);
PAINT MONO (3420 1250);
FORCEPROP 2 LAST CDS_LIB standard
J 0
(3675 1250);
DISPLAY INVISIBLE (3675 1250);
FORCEPROP 1 LAST COMMENT_BODY TRUE
J 2
(3720 1155);
DISPLAY 0.872340 (3720 1155);
PAINT GREEN (3720 1155);
DISPLAY INVISIBLE (3720 1155);
FORCEPROP 1 LAST OFFPAGE TRUE
J 2
(3350 1125);
DISPLAY 0.872340 (3350 1125);
PAINT AQUA (3350 1125);
DISPLAY INVISIBLE (3350 1125);
FORCEPROP 2 LAST PATH I87
J 0
(3400 1300);
DISPLAY 1.021277 (3400 1300);
DISPLAY INVISIBLE (3400 1300);
FORCEADD OFFPAGE..2
R 2
(-1250 1250);
FORCEPROP 2 LAST $XR0 145 
J 0
(-1535 1250);
DISPLAY 0.638298 (-1535 1250);
PAINT MONO (-1535 1250);
FORCEPROP 2 LAST CDS_LIB standard
J 0
(-1250 1250);
DISPLAY INVISIBLE (-1250 1250);
FORCEPROP 1 LAST COMMENT_BODY TRUE
J 2
(-1205 1155);
DISPLAY 0.872340 (-1205 1155);
PAINT GREEN (-1205 1155);
DISPLAY INVISIBLE (-1205 1155);
FORCEPROP 1 LAST OFFPAGE TRUE
J 2
(-1575 1125);
DISPLAY 0.872340 (-1575 1125);
PAINT AQUA (-1575 1125);
DISPLAY INVISIBLE (-1575 1125);
FORCEPROP 2 LAST PATH I88
J 0
(-1525 1300);
DISPLAY 1.021277 (-1525 1300);
DISPLAY INVISIBLE (-1525 1300);
FORCEADD OFFPAGE..2
R 2
(-1250 2850);
FORCEPROP 2 LAST $XR0 145 
J 0
(-1535 2850);
DISPLAY 0.638298 (-1535 2850);
PAINT MONO (-1535 2850);
FORCEPROP 2 LAST CDS_LIB standard
J 0
(-1250 2850);
DISPLAY INVISIBLE (-1250 2850);
FORCEPROP 1 LAST COMMENT_BODY TRUE
J 2
(-1205 2755);
DISPLAY 0.872340 (-1205 2755);
PAINT GREEN (-1205 2755);
DISPLAY INVISIBLE (-1205 2755);
FORCEPROP 1 LAST OFFPAGE TRUE
J 2
(-1575 2725);
DISPLAY 0.872340 (-1575 2725);
PAINT AQUA (-1575 2725);
DISPLAY INVISIBLE (-1575 2725);
FORCEPROP 2 LAST PATH I89
J 0
(-1525 2900);
DISPLAY 1.021277 (-1525 2900);
DISPLAY INVISIBLE (-1525 2900);
FORCEADD OFFPAGE..2
R 2
(-1250 1150);
FORCEPROP 2 LAST $XR0 30 
J 0
(-1504 1150);
DISPLAY 0.638298 (-1504 1150);
PAINT MONO (-1504 1150);
FORCEPROP 2 LAST CDS_LIB standard
J 0
(-1250 1150);
DISPLAY INVISIBLE (-1250 1150);
FORCEPROP 1 LAST OFFPAGE TRUE
J 2
(-1575 1025);
DISPLAY 0.872340 (-1575 1025);
PAINT AQUA (-1575 1025);
DISPLAY INVISIBLE (-1575 1025);
FORCEPROP 1 LAST COMMENT_BODY TRUE
J 2
(-1205 1055);
DISPLAY 0.872340 (-1205 1055);
PAINT GREEN (-1205 1055);
DISPLAY INVISIBLE (-1205 1055);
FORCEPROP 2 LAST PATH I9
J 0
(-1200 1225);
DISPLAY 1.021277 (-1200 1225);
DISPLAY INVISIBLE (-1200 1225);
FORCEADD QUANTA_TITLE_BLOCK_C..1
(6950 -1625);
FORCEPROP 0 LAST CDS_CON_LAST_MODIFIED Fri Aug 25 14:01:57 2023
J 0
(5065 -1610);
PAINT MONO (5065 -1610);
DISPLAY INVISIBLE (5065 -1610);
FORCEPROP 2 LAST CUSTOM_TXT_CDS <XR_PAGE_TITLE>
J 0
(-940 3625);
DISPLAY 0.638298 (-940 3625);
PAINT PINK (-940 3625);
DISPLAY INVISIBLE (-940 3625);
FORCEPROP 2 LAST CUSTOM_TXT_CDS <CON_PAGE_NUM> OF <CON_TOTAL_PAGES>
J 0
(6504 -1607);
DISPLAY 0.978723 (6504 -1607);
FORCEPROP 2 LAST CUSTOM_TXT_CDS <Q_NUMBER>
J 0
(5547 -1522);
DISPLAY 1.212766 (5547 -1522);
FORCEPROP 2 LAST CUSTOM_TXT_CDS <CON_LAST_MODIFIED>
J 0
(5100 -1625);
DISPLAY 0.978723 (5100 -1625);
FORCEPROP 2 LAST CUSTOM_TXT_CDS <NAME_1>
J 0
(3775 -1450);
FORCEPROP 2 LAST CUSTOM_TXT_CDS <Q_REV>
J 0
(6766 -1522);
DISPLAY 1.212766 (6766 -1522);
FORCEPROP 2 LAST CUSTOM_TXT_CDS <NAME_2>
J 0
(3775 -1575);
FORCEPROP 2 LAST CUSTOM_TXT_CDS <Q_PROJ>
J 0
(4568 -1523);
DISPLAY 1.212766 (4568 -1523);
FORCEPROP 1 LAST Q_TITLE PCIE - CPU0_EXAMAX_P2/P3_X16
J 0
(-2325 -1575);
DISPLAY 1.957447 (-2325 -1575);
PAINT GREEN (-2325 -1575);
FORCEPROP 1 LAST Q_DEPT 
J 1
(3187 -1576);
DISPLAY 1.957447 (3187 -1576);
PAINT GREEN (3187 -1576);
FORCEPROP 2 LAST CDS_XR_PAGE_TITLE CR-136 : @S9S_MB_2U_LIB.S9S_MB_2U(SCH_1):PAGE136
J 0
(-940 3625);
DISPLAY 0.638298 (-940 3625);
PAINT PINK (-940 3625);
DISPLAY INVISIBLE (-940 3625);
FORCEPROP 1 LAST CDS_LMAN_SYM_OUTLINE -9475,6775,100,-125
J 0
(6950 -1625);
DISPLAY 0.468085 (6950 -1625);
PAINT GREEN (6950 -1625);
DISPLAY INVISIBLE (6950 -1625);
FORCEPROP 2 LAST CDS_LIB pure_quanta
J 0
(6950 -1625);
PAINT MONO (6950 -1625);
DISPLAY INVISIBLE (6950 -1625);
FORCEPROP 1 LAST COMMENT_BODY TRUE
J 0
(6962 -1638);
DISPLAY 0.978723 (6962 -1638);
PAINT GREEN (6962 -1638);
DISPLAY INVISIBLE (6962 -1638);
FORCEPROP 2 LAST PAGE_BORDER TRUE
J 0
(-940 3625);
DISPLAY 0.638298 (-940 3625);
PAINT PINK (-940 3625);
DISPLAY INVISIBLE (-940 3625);
WIRE 16 -1 (4725 600)(4725 250);
WIRE 16 -1 (4725 750)(4725 600);
WIRE 16 -1 (4950 600)(4725 600);
WIRE 16 -1 (-150 600)(-150 300);
WIRE 16 -1 (-150 750)(-150 600);
WIRE 16 -1 (25 600)(-150 600);
WIRE 16 -1 (25 1650)(-1200 1650);
FORCEPROP 2 LAST SIG_NAME P5E_CPU0_PE3_TX_C_DP<2>
J 0
(-1035 1660);
DISPLAY 0.638298 (-1035 1660);
WIRE 16 -1 (25 2850)(-1200 2850);
FORCEPROP 2 LAST SIG_NAME GPU_3V3IO_RSVD1
J 0
(-1035 2860);
DISPLAY 0.638298 (-1035 2860);
WIRE 16 -1 (25 1250)(-1200 1250);
FORCEPROP 2 LAST SIG_NAME GPU_3V3IO_RSVD3
J 0
(-1035 1260);
DISPLAY 0.638298 (-1035 1260);
WIRE 16 -1 (4950 1250)(3725 1250);
FORCEPROP 2 LAST SIG_NAME GPU_3V3IO_RSVD4
J 0
(3865 1260);
DISPLAY 0.638298 (3865 1260);
WIRE 16 -1 (25 2750)(-1200 2750);
FORCEPROP 2 LAST SIG_NAME P5E_CPU0_PE3_RX_DN<1>
J 0
(-1035 2760);
DISPLAY 0.638298 (-1035 2760);
WIRE 16 -1 (25 2700)(-1200 2700);
FORCEPROP 2 LAST SIG_NAME P5E_CPU0_PE3_RX_DP<1>
J 0
(-1035 2710);
DISPLAY 0.638298 (-1035 2710);
WIRE 16 -1 (25 2600)(-1200 2600);
FORCEPROP 2 LAST SIG_NAME P5E_CPU0_PE2_RX_DP<1>
J 0
(-1035 2610);
DISPLAY 0.638298 (-1035 2610);
WIRE 16 -1 (25 2550)(-1200 2550);
FORCEPROP 2 LAST SIG_NAME P5E_CPU0_PE2_RX_DN<1>
J 0
(-1035 2560);
DISPLAY 0.638298 (-1035 2560);
WIRE 16 -1 (25 2450)(-1200 2450);
FORCEPROP 2 LAST SIG_NAME P5E_CPU0_PE3_TX_C_DN<1>
J 0
(-1035 2460);
DISPLAY 0.638298 (-1035 2460);
WIRE 16 -1 (25 2400)(-1200 2400);
FORCEPROP 2 LAST SIG_NAME P5E_CPU0_PE3_TX_C_DP<1>
J 0
(-1035 2410);
DISPLAY 0.638298 (-1035 2410);
WIRE 16 -1 (25 2300)(-1200 2300);
FORCEPROP 2 LAST SIG_NAME P5E_CPU0_PE2_TX_C_DP<1>
J 0
(-1035 2310);
DISPLAY 0.638298 (-1035 2310);
WIRE 16 -1 (25 2250)(-1200 2250);
FORCEPROP 2 LAST SIG_NAME P5E_CPU0_PE2_TX_C_DN<1>
J 0
(-1035 2260);
DISPLAY 0.638298 (-1035 2260);
WIRE 16 -1 (25 2000)(-1200 2000);
FORCEPROP 2 LAST SIG_NAME P5E_CPU0_PE3_RX_DN<2>
J 0
(-1035 2010);
DISPLAY 0.638298 (-1035 2010);
WIRE 16 -1 (25 1950)(-1200 1950);
FORCEPROP 2 LAST SIG_NAME P5E_CPU0_PE3_RX_DP<2>
J 0
(-1035 1960);
DISPLAY 0.638298 (-1035 1960);
WIRE 16 -1 (25 1850)(-1200 1850);
FORCEPROP 2 LAST SIG_NAME P5E_CPU0_PE2_RX_DP<2>
J 0
(-1035 1860);
DISPLAY 0.638298 (-1035 1860);
WIRE 16 -1 (25 1800)(-1200 1800);
FORCEPROP 2 LAST SIG_NAME P5E_CPU0_PE2_RX_DN<2>
J 0
(-1035 1810);
DISPLAY 0.638298 (-1035 1810);
WIRE 16 -1 (25 1400)(-1200 1400);
FORCEPROP 2 LAST SIG_NAME RST_SWB_BIC_BUF_N
J 0
(-1035 1410);
DISPLAY 0.638298 (-1035 1410);
WIRE 16 -1 (25 3650)(-150 3650);
WIRE 16 -1 (-150 3650)(-150 3500);
WIRE 16 -1 (25 3500)(-150 3500);
WIRE 16 -1 (-150 3500)(-150 3350);
WIRE 16 -1 (25 3350)(-150 3350);
WIRE 16 -1 (-150 3350)(-150 3200);
WIRE 16 -1 (25 3200)(-150 3200);
WIRE 16 -1 (-150 3200)(-150 3050);
WIRE 16 -1 (25 3050)(-150 3050);
WIRE 16 -1 (-150 3050)(-150 2800);
WIRE 16 -1 (25 2800)(-150 2800);
WIRE 16 -1 (-150 2800)(-150 2650);
WIRE 16 -1 (25 2650)(-150 2650);
WIRE 16 -1 (-150 2650)(-150 2500);
WIRE 16 -1 (25 2500)(-150 2500);
WIRE 16 -1 (-150 2500)(-150 2350);
WIRE 16 -1 (25 2350)(-150 2350);
WIRE 16 -1 (-150 2350)(-150 2200);
WIRE 16 -1 (25 2200)(-150 2200);
WIRE 16 -1 (-150 2200)(-150 2050);
WIRE 16 -1 (25 2050)(-150 2050);
WIRE 16 -1 (-150 2050)(-150 1900);
WIRE 16 -1 (25 1900)(-150 1900);
WIRE 16 -1 (-150 1900)(-150 1750);
WIRE 16 -1 (25 1750)(-150 1750);
WIRE 16 -1 (-150 1750)(-150 1600);
WIRE 16 -1 (25 1600)(-150 1600);
WIRE 16 -1 (-150 1600)(-150 1450);
WIRE 16 -1 (25 1450)(-150 1450);
WIRE 16 -1 (-150 1450)(-150 1200);
WIRE 16 -1 (25 1200)(-150 1200);
WIRE 16 -1 (-150 1050)(-150 1200);
WIRE 16 -1 (25 1050)(-150 1050);
WIRE 16 -1 (-150 900)(-150 1050);
WIRE 16 -1 (25 900)(-150 900);
WIRE 16 -1 (-150 900)(-150 750);
WIRE 16 -1 (25 750)(-150 750);
WIRE 16 -1 (4950 1150)(3725 1150);
FORCEPROP 2 LAST SIG_NAME P5E_CPU0_PE3_RX_DP<7>
J 0
(3865 1160);
DISPLAY 0.638298 (3865 1160);
WIRE 16 -1 (4950 1100)(3725 1100);
FORCEPROP 2 LAST SIG_NAME P5E_CPU0_PE3_RX_DN<7>
J 0
(3865 1110);
DISPLAY 0.638298 (3865 1110);
WIRE 16 -1 (25 1700)(-1200 1700);
FORCEPROP 2 LAST SIG_NAME P5E_CPU0_PE3_TX_C_DN<2>
J 0
(-1035 1710);
DISPLAY 0.638298 (-1035 1710);
WIRE 16 -1 (25 1500)(-1200 1500);
FORCEPROP 2 LAST SIG_NAME P5E_CPU0_PE2_TX_C_DN<2>
J 0
(-1035 1510);
DISPLAY 0.638298 (-1035 1510);
WIRE 16 -1 (4950 3650)(4725 3650);
WIRE 16 -1 (4950 3500)(4725 3500);
WIRE 16 -1 (4725 3650)(4725 3500);
WIRE 16 -1 (4725 3500)(4725 3350);
WIRE 16 -1 (4950 3350)(4725 3350);
WIRE 16 -1 (4725 3350)(4725 3200);
WIRE 16 -1 (4950 3200)(4725 3200);
WIRE 16 -1 (4950 3050)(4725 3050);
WIRE 16 -1 (4725 3200)(4725 3050);
WIRE 16 -1 (4725 3050)(4725 2800);
WIRE 16 -1 (4950 2800)(4725 2800);
WIRE 16 -1 (4725 2800)(4725 2650);
WIRE 16 -1 (4950 2650)(4725 2650);
WIRE 16 -1 (4950 2500)(4725 2500);
WIRE 16 -1 (4725 2650)(4725 2500);
WIRE 16 -1 (4725 2500)(4725 2350);
WIRE 16 -1 (4950 2350)(4725 2350);
WIRE 16 -1 (4725 2350)(4725 2200);
WIRE 16 -1 (4950 2200)(4725 2200);
WIRE 16 -1 (4725 2200)(4725 2050);
WIRE 16 -1 (4950 2050)(4725 2050);
WIRE 16 -1 (4950 1900)(4725 1900);
WIRE 16 -1 (4725 2050)(4725 1900);
WIRE 16 -1 (4725 1900)(4725 1750);
WIRE 16 -1 (4950 1750)(4725 1750);
WIRE 16 -1 (4725 1750)(4725 1600);
WIRE 16 -1 (4950 1600)(4725 1600);
WIRE 16 -1 (4950 1450)(4725 1450);
WIRE 16 -1 (4725 1600)(4725 1450);
WIRE 16 -1 (4725 1450)(4725 1200);
WIRE 16 -1 (4950 1200)(4725 1200);
WIRE 16 -1 (4725 1200)(4725 1050);
WIRE 16 -1 (4950 1050)(4725 1050);
WIRE 16 -1 (4950 900)(4725 900);
WIRE 16 -1 (4725 1050)(4725 900);
WIRE 16 -1 (4725 900)(4725 750);
WIRE 16 -1 (4950 750)(4725 750);
WIRE 16 -1 (4950 1000)(3725 1000);
FORCEPROP 2 LAST SIG_NAME P5E_CPU0_PE2_RX_DP<7>
J 0
(3865 1010);
DISPLAY 0.638298 (3865 1010);
WIRE 16 -1 (4950 2400)(3700 2400);
FORCEPROP 2 LAST SIG_NAME P5E_CPU0_PE3_TX_C_DP<5>
J 0
(3865 2410);
DISPLAY 0.638298 (3865 2410);
WIRE 16 -1 (4950 3250)(3700 3250);
FORCEPROP 2 LAST SIG_NAME P5E_CPU0_PE3_TX_C_DP<4>
J 0
(3865 3260);
DISPLAY 0.638298 (3865 3260);
WIRE 16 -1 (4950 3300)(3700 3300);
FORCEPROP 2 LAST SIG_NAME P5E_CPU0_PE3_TX_C_DN<4>
J 0
(3865 3310);
DISPLAY 0.638298 (3865 3310);
WIRE 16 -1 (4950 3150)(3700 3150);
FORCEPROP 2 LAST SIG_NAME P5E_CPU0_PE2_TX_C_DP<4>
J 0
(3865 3160);
DISPLAY 0.638298 (3865 3160);
WIRE 16 -1 (4950 3100)(3700 3100);
FORCEPROP 2 LAST SIG_NAME P5E_CPU0_PE2_TX_C_DN<4>
J 0
(3865 3110);
DISPLAY 0.638298 (3865 3110);
WIRE 16 -1 (4950 3000)(3700 3000);
FORCEPROP 2 LAST SIG_NAME FM_SWB_BIC_READY_N
J 0
(3865 3010);
DISPLAY 0.638298 (3865 3010);
WIRE 16 -1 (4950 2850)(3700 2850);
FORCEPROP 2 LAST SIG_NAME GPU_WP_HW_CTRL_ISO
J 0
(3865 2860);
DISPLAY 0.638298 (3865 2860);
WIRE 16 -1 (4950 2750)(3700 2750);
FORCEPROP 2 LAST SIG_NAME P5E_CPU0_PE3_RX_DP<5>
J 0
(3865 2760);
DISPLAY 0.638298 (3865 2760);
WIRE 16 -1 (4950 2700)(3700 2700);
FORCEPROP 2 LAST SIG_NAME P5E_CPU0_PE3_RX_DN<5>
J 0
(3865 2710);
DISPLAY 0.638298 (3865 2710);
WIRE 16 -1 (4950 2600)(3700 2600);
FORCEPROP 2 LAST SIG_NAME P5E_CPU0_PE2_RX_DP<5>
J 0
(3865 2610);
DISPLAY 0.638298 (3865 2610);
WIRE 16 -1 (4950 2550)(3700 2550);
FORCEPROP 2 LAST SIG_NAME P5E_CPU0_PE2_RX_DN<5>
J 0
(3865 2560);
DISPLAY 0.638298 (3865 2560);
WIRE 16 -1 (4950 2450)(3700 2450);
FORCEPROP 2 LAST SIG_NAME P5E_CPU0_PE3_TX_C_DN<5>
J 0
(3865 2460);
DISPLAY 0.638298 (3865 2460);
WIRE 16 -1 (4950 2250)(3700 2250);
FORCEPROP 2 LAST SIG_NAME P5E_CPU0_PE2_TX_C_DN<5>
J 0
(3865 2260);
DISPLAY 0.638298 (3865 2260);
WIRE 16 -1 (4950 2000)(3725 2000);
FORCEPROP 2 LAST SIG_NAME P5E_CPU0_PE3_RX_DP<6>
J 0
(3865 2010);
DISPLAY 0.638298 (3865 2010);
WIRE 16 -1 (4950 1950)(3725 1950);
FORCEPROP 2 LAST SIG_NAME P5E_CPU0_PE3_RX_DN<6>
J 0
(3865 1960);
DISPLAY 0.638298 (3865 1960);
WIRE 16 -1 (4950 1800)(3725 1800);
FORCEPROP 2 LAST SIG_NAME P5E_CPU0_PE2_RX_DN<6>
J 0
(3865 1810);
DISPLAY 0.638298 (3865 1810);
WIRE 16 -1 (4950 1400)(3725 1400);
FORCEPROP 2 LAST SIG_NAME FM_SWB_PWR_EN_R_BUF
J 0
(3865 1410);
DISPLAY 0.638298 (3865 1410);
WIRE 16 -1 (4950 1500)(3725 1500);
FORCEPROP 2 LAST SIG_NAME P5E_CPU0_PE2_TX_C_DN<6>
J 0
(3865 1510);
DISPLAY 0.638298 (3865 1510);
WIRE 16 -1 (4950 1650)(3725 1650);
FORCEPROP 2 LAST SIG_NAME P5E_CPU0_PE3_TX_C_DP<6>
J 0
(3865 1660);
DISPLAY 0.638298 (3865 1660);
WIRE 16 -1 (4950 1550)(3725 1550);
FORCEPROP 2 LAST SIG_NAME P5E_CPU0_PE2_TX_C_DP<6>
J 0
(3865 1560);
DISPLAY 0.638298 (3865 1560);
WIRE 16 -1 (4950 1850)(3725 1850);
FORCEPROP 2 LAST SIG_NAME P5E_CPU0_PE2_RX_DP<6>
J 0
(3865 1860);
DISPLAY 0.638298 (3865 1860);
WIRE 16 -1 (4950 1700)(3725 1700);
FORCEPROP 2 LAST SIG_NAME P5E_CPU0_PE3_TX_C_DN<6>
J 0
(3865 1710);
DISPLAY 0.638298 (3865 1710);
WIRE 16 -1 (25 3000)(-1200 3000);
FORCEPROP 2 LAST SIG_NAME RST_BMC_FROM_SWB_N
J 0
(-1035 3010);
DISPLAY 0.638298 (-1035 3010);
WIRE 16 -1 (25 3600)(-1200 3600);
FORCEPROP 2 LAST SIG_NAME P5E_CPU0_PE3_RX_DP<0>
J 0
(-1035 3610);
DISPLAY 0.638298 (-1035 3610);
WIRE 16 -1 (25 3550)(-1200 3550);
FORCEPROP 2 LAST SIG_NAME P5E_CPU0_PE3_RX_DN<0>
J 0
(-1035 3560);
DISPLAY 0.638298 (-1035 3560);
WIRE 16 -1 (25 1150)(-1200 1150);
FORCEPROP 2 LAST SIG_NAME P5E_CPU0_PE3_RX_DN<3>
J 0
(-1035 1160);
DISPLAY 0.638298 (-1035 1160);
WIRE 16 -1 (25 1100)(-1200 1100);
FORCEPROP 2 LAST SIG_NAME P5E_CPU0_PE3_RX_DP<3>
J 0
(-1035 1110);
DISPLAY 0.638298 (-1035 1110);
WIRE 16 -1 (25 3450)(-1200 3450);
FORCEPROP 2 LAST SIG_NAME P5E_CPU0_PE2_RX_DP<0>
J 0
(-1035 3460);
DISPLAY 0.638298 (-1035 3460);
WIRE 16 -1 (25 3400)(-1200 3400);
FORCEPROP 2 LAST SIG_NAME P5E_CPU0_PE2_RX_DN<0>
J 0
(-1035 3410);
DISPLAY 0.638298 (-1035 3410);
WIRE 16 -1 (25 1000)(-1200 1000);
FORCEPROP 2 LAST SIG_NAME P5E_CPU0_PE2_RX_DP<3>
J 0
(-1035 1010);
DISPLAY 0.638298 (-1035 1010);
WIRE 16 -1 (25 950)(-1200 950);
FORCEPROP 2 LAST SIG_NAME P5E_CPU0_PE2_RX_DN<3>
J 0
(-1035 960);
DISPLAY 0.638298 (-1035 960);
WIRE 16 -1 (25 3300)(-1200 3300);
FORCEPROP 2 LAST SIG_NAME P5E_CPU0_PE3_TX_C_DP<0>
J 0
(-1035 3310);
DISPLAY 0.638298 (-1035 3310);
WIRE 16 -1 (25 3250)(-1200 3250);
FORCEPROP 2 LAST SIG_NAME P5E_CPU0_PE3_TX_C_DN<0>
J 0
(-1035 3260);
DISPLAY 0.638298 (-1035 3260);
WIRE 16 -1 (25 850)(-1200 850);
FORCEPROP 2 LAST SIG_NAME P5E_CPU0_PE3_TX_C_DN<3>
J 0
(-1035 860);
DISPLAY 0.638298 (-1035 860);
WIRE 16 -1 (25 800)(-1200 800);
FORCEPROP 2 LAST SIG_NAME P5E_CPU0_PE3_TX_C_DP<3>
J 0
(-1035 810);
DISPLAY 0.638298 (-1035 810);
WIRE 16 -1 (25 3150)(-1200 3150);
FORCEPROP 2 LAST SIG_NAME P5E_CPU0_PE2_TX_C_DP<0>
J 0
(-1035 3160);
DISPLAY 0.638298 (-1035 3160);
WIRE 16 -1 (25 1550)(-1200 1550);
FORCEPROP 2 LAST SIG_NAME P5E_CPU0_PE2_TX_C_DP<2>
J 0
(-1035 1560);
DISPLAY 0.638298 (-1035 1560);
WIRE 16 -1 (25 3100)(-1200 3100);
FORCEPROP 2 LAST SIG_NAME P5E_CPU0_PE2_TX_C_DN<0>
J 0
(-1035 3110);
DISPLAY 0.638298 (-1035 3110);
WIRE 16 -1 (25 700)(-1200 700);
FORCEPROP 2 LAST SIG_NAME P5E_CPU0_PE2_TX_C_DP<3>
J 0
(-1035 710);
DISPLAY 0.638298 (-1035 710);
WIRE 16 -1 (25 650)(-1200 650);
FORCEPROP 2 LAST SIG_NAME P5E_CPU0_PE2_TX_C_DN<3>
J 0
(-1035 660);
DISPLAY 0.638298 (-1035 660);
WIRE 16 -1 (4950 3400)(3700 3400);
FORCEPROP 2 LAST SIG_NAME P5E_CPU0_PE2_RX_DN<4>
J 0
(3865 3410);
DISPLAY 0.638298 (3865 3410);
WIRE 16 -1 (4950 3550)(3700 3550);
FORCEPROP 2 LAST SIG_NAME P5E_CPU0_PE3_RX_DN<4>
J 0
(3865 3560);
DISPLAY 0.638298 (3865 3560);
WIRE 16 -1 (4950 700)(3725 700);
FORCEPROP 2 LAST SIG_NAME P5E_CPU0_PE2_TX_C_DP<7>
J 0
(3865 710);
DISPLAY 0.638298 (3865 710);
WIRE 16 -1 (4950 650)(3725 650);
FORCEPROP 2 LAST SIG_NAME P5E_CPU0_PE2_TX_C_DN<7>
J 0
(3865 660);
DISPLAY 0.638298 (3865 660);
WIRE 16 -1 (4950 800)(3725 800);
FORCEPROP 2 LAST SIG_NAME P5E_CPU0_PE3_TX_C_DP<7>
J 0
(3865 810);
DISPLAY 0.638298 (3865 810);
WIRE 16 -1 (4950 850)(3725 850);
FORCEPROP 2 LAST SIG_NAME P5E_CPU0_PE3_TX_C_DN<7>
J 0
(3865 860);
DISPLAY 0.638298 (3865 860);
WIRE 16 -1 (4950 950)(3725 950);
FORCEPROP 2 LAST SIG_NAME P5E_CPU0_PE2_RX_DN<7>
J 0
(3865 960);
DISPLAY 0.638298 (3865 960);
WIRE 16 -1 (4950 2300)(3700 2300);
FORCEPROP 2 LAST SIG_NAME P5E_CPU0_PE2_TX_C_DP<5>
J 0
(3865 2310);
DISPLAY 0.638298 (3865 2310);
WIRE 16 -1 (4950 3450)(3700 3450);
FORCEPROP 2 LAST SIG_NAME P5E_CPU0_PE2_RX_DP<4>
J 0
(3865 3460);
DISPLAY 0.638298 (3865 3460);
WIRE 16 -1 (4950 3600)(3700 3600);
FORCEPROP 2 LAST SIG_NAME P5E_CPU0_PE3_RX_DP<4>
J 0
(3865 3610);
DISPLAY 0.638298 (3865 3610);
DOT 1 (-150 3050);
DOT 1 (4725 2500);
DOT 1 (4725 3200);
DOT 1 (4725 2650);
DOT 1 (-150 2650);
DOT 1 (-150 1200);
DOT 1 (-150 2800);
DOT 1 (-150 900);
DOT 1 (-150 3350);
DOT 1 (-150 3500);
DOT 1 (-150 3200);
DOT 1 (-150 2500);
DOT 1 (-150 2350);
DOT 1 (-150 2200);
DOT 1 (-150 2050);
DOT 1 (-150 1900);
DOT 1 (-150 1750);
DOT 1 (-150 1600);
DOT 1 (-150 1450);
DOT 1 (-150 1050);
DOT 1 (-150 600);
DOT 1 (-150 750);
DOT 1 (4725 3500);
DOT 1 (4725 3350);
DOT 1 (4725 3050);
DOT 1 (4725 2800);
DOT 1 (4725 2350);
DOT 1 (4725 2200);
DOT 1 (4725 2050);
DOT 1 (4725 1900);
DOT 1 (4725 1750);
DOT 1 (4725 1600);
DOT 1 (4725 1450);
DOT 1 (4725 1200);
DOT 1 (4725 1050);
DOT 1 (4725 900);
DOT 1 (4725 600);
DOT 1 (4725 750);
FORCENOTE
DP/DN SWAP
(2875 975) 0;
DISPLAY LEFT (2875 975);
DISPLAY 1.021277 (2875 975);
FORCENOTE
DP/DN SWAP
(2900 1500) 0;
DISPLAY LEFT (2900 1500);
DISPLAY 1.021277 (2900 1500);
FORCENOTE
DP/DN SWAP
(2875 1800) 0;
DISPLAY LEFT (2875 1800);
DISPLAY 1.021277 (2875 1800);
FORCENOTE
DP/DN SWAP
(-2075 3575) 0;
DISPLAY LEFT (-2075 3575);
DISPLAY 1.021277 (-2075 3575);
FORCENOTE
DP/DN SWAP
(2850 3400) 0;
DISPLAY LEFT (2850 3400);
DISPLAY 1.021277 (2850 3400);
FORCENOTE
DP/DN SWAP
(-2050 3100) 0;
DISPLAY LEFT (-2050 3100);
DISPLAY 1.021277 (-2050 3100);
FORCENOTE
DP/DN SWAP
(-2075 2250) 0;
DISPLAY LEFT (-2075 2250);
DISPLAY 1.021277 (-2075 2250);
FORCENOTE
DP/DN SWAP
(-2075 1500) 0;
DISPLAY LEFT (-2075 1500);
DISPLAY 1.021277 (-2075 1500);
FORCENOTE
DP/DN SWAP
(-2050 650) 0;
DISPLAY LEFT (-2050 650);
DISPLAY 1.021277 (-2050 650);
FORCENOTE
DP/DN SWAP
(2875 650) 0;
DISPLAY LEFT (2875 650);
DISPLAY 1.021277 (2875 650);
FORCENOTE
DP/DN SWAP
(2850 2250) 0;
DISPLAY LEFT (2850 2250);
DISPLAY 1.021277 (2850 2250);
FORCENOTE
DP/DN SWAP
(2850 2725) 0;
DISPLAY LEFT (2850 2725);
DISPLAY 1.021277 (2850 2725);
FORCENOTE
DP/DN SWAP
(2875 3075) 0;
DISPLAY LEFT (2875 3075);
DISPLAY 1.021277 (2875 3075);
FORCENOTE
DP/DN SWAP
(-2075 3275) 0;
DISPLAY LEFT (-2075 3275);
DISPLAY 1.021277 (-2075 3275);
FORCENOTE
20210527 MODIFY FOR GT
(-2225 4750) 0;
DISPLAY LEFT (-2225 4750);
DISPLAY 2.510638 (-2225 4750);
PAINT PINK (-2225 4750);
FORCENOTE
DP/DN SWAP
(-2075 3425) 0;
DISPLAY LEFT (-2075 3425);
DISPLAY 1.021277 (-2075 3425);
FORCENOTE
DP/DN SWAP
(-2075 2550) 0;
DISPLAY LEFT (-2075 2550);
DISPLAY 1.021277 (-2075 2550);
FORCENOTE
DP/DN SWAP
(-2075 1800) 0;
DISPLAY LEFT (-2075 1800);
DISPLAY 1.021277 (-2075 1800);
FORCENOTE
DP/DN SWAP
(-2075 975) 0;
DISPLAY LEFT (-2075 975);
DISPLAY 1.021277 (-2075 975);
FORCENOTE
DP/DN SWAP
(2875 1950) 0;
DISPLAY LEFT (2875 1950);
DISPLAY 1.021277 (2875 1950);
FORCENOTE
DP/DN SWAP
(2850 2575) 0;
DISPLAY LEFT (2850 2575);
DISPLAY 1.021277 (2850 2575);
FORCENOTE
DP/DN SWAP
(2850 3575) 0;
DISPLAY LEFT (2850 3575);
DISPLAY 1.021277 (2850 3575);
FORCENOTE
DP/DN SWAP
(2875 1125) 0;
DISPLAY LEFT (2875 1125);
DISPLAY 1.021277 (2875 1125);
QUIT
